FILE_TYPE = MACRO_DRAWING;
SET COLOR_WIRE YELLOW;
SET COLOR_PROP ORANGE;
SET COLOR_DOT WHITE;
SET COLOR_ARC YELLOW;
SET COLOR_BODY GREEN;
SET COLOR_NOTE PURPLE;
SET PROP_DISPLAY VALUE;
SET PAGE_NUMBER P134;
FORCEADD OFFPAGE..1
(-2000 -150);
FORCEPROP 2 LAST $XR2 132 
J 0
(-2522 -150);
DISPLAY 0.638298 (-2522 -150);
PAINT MONO (-2522 -150);
FORCEPROP 2 LAST $XR1 239 
J 0
(-2402 -150);
DISPLAY 0.638298 (-2402 -150);
PAINT MONO (-2402 -150);
FORCEPROP 2 LAST $XR0 131 
J 0
(-2282 -150);
DISPLAY 0.638298 (-2282 -150);
PAINT MONO (-2282 -150);
FORCEPROP 2 LAST CDS_LIB standard
J 0
(-2000 -150);
PAINT MONO (-2000 -150);
DISPLAY INVISIBLE (-2000 -150);
FORCEPROP 1 LAST OFFPAGE TRUE
J 0
(-1675 -275);
DISPLAY 0.872340 (-1675 -275);
PAINT GREEN (-1675 -275);
DISPLAY INVISIBLE (-1675 -275);
FORCEPROP 1 LAST COMMENT_BODY TRUE
J 0
(-1875 -250);
DISPLAY 0.872340 (-1875 -250);
PAINT GREEN (-1875 -250);
DISPLAY INVISIBLE (-1875 -250);
FORCEPROP 2 LAST PATH I116
J 0
(-2275 -100);
DISPLAY 1.021277 (-2275 -100);
DISPLAY INVISIBLE (-2275 -100);
FORCEADD OFFPAGE..1
(-2000 -75);
FORCEPROP 2 LAST $XR2 132 
J 0
(-2522 -75);
DISPLAY 0.638298 (-2522 -75);
PAINT MONO (-2522 -75);
FORCEPROP 2 LAST $XR1 239 
J 0
(-2402 -75);
DISPLAY 0.638298 (-2402 -75);
PAINT MONO (-2402 -75);
FORCEPROP 2 LAST $XR0 131 
J 0
(-2282 -75);
DISPLAY 0.638298 (-2282 -75);
PAINT MONO (-2282 -75);
FORCEPROP 2 LAST CDS_LIB standard
J 0
(-2000 -75);
PAINT MONO (-2000 -75);
DISPLAY INVISIBLE (-2000 -75);
FORCEPROP 1 LAST OFFPAGE TRUE
J 0
(-1675 -200);
DISPLAY 0.872340 (-1675 -200);
PAINT GREEN (-1675 -200);
DISPLAY INVISIBLE (-1675 -200);
FORCEPROP 1 LAST COMMENT_BODY TRUE
J 0
(-1875 -175);
DISPLAY 0.872340 (-1875 -175);
PAINT GREEN (-1875 -175);
DISPLAY INVISIBLE (-1875 -175);
FORCEPROP 2 LAST PATH I117
J 0
(-2275 -25);
DISPLAY 1.021277 (-2275 -25);
DISPLAY INVISIBLE (-2275 -25);
FORCEADD OFFPAGE..4
(2575 0);
FORCEPROP 2 LAST $XR0 182 
J 0
(2761 0);
DISPLAY 0.638298 (2761 0);
PAINT MONO (2761 0);
FORCEPROP 2 LAST CDS_LIB standard
J 0
(2575 0);
PAINT MONO (2575 0);
DISPLAY INVISIBLE (2575 0);
FORCEPROP 1 LAST OFFPAGE TRUE
J 0
(2900 -125);
DISPLAY 1.170213 (2900 -125);
PAINT GREEN (2900 -125);
DISPLAY INVISIBLE (2900 -125);
FORCEPROP 1 LAST COMMENT_BODY TRUE
J 0
(2550 -100);
DISPLAY 1.170213 (2550 -100);
PAINT GREEN (2550 -100);
DISPLAY INVISIBLE (2550 -100);
FORCEPROP 2 LAST PATH I124
J 0
(2750 75);
DISPLAY 1.021277 (2750 75);
DISPLAY INVISIBLE (2750 75);
FORCEADD OFFPAGE..2
R 2
(-2000 0);
FORCEPROP 2 LAST $XR2 239 
J 0
(-2495 0);
DISPLAY 0.638298 (-2495 0);
PAINT MONO (-2495 0);
FORCEPROP 2 LAST $XR1 131 
J 0
(-2375 0);
DISPLAY 0.638298 (-2375 0);
PAINT MONO (-2375 0);
FORCEPROP 2 LAST $XR0 132 
J 0
(-2255 0);
DISPLAY 0.638298 (-2255 0);
PAINT MONO (-2255 0);
FORCEPROP 2 LAST CDS_LIB standard
J 0
(-2000 0);
PAINT MONO (-2000 0);
DISPLAY INVISIBLE (-2000 0);
FORCEPROP 1 LAST OFFPAGE TRUE
J 2
(-2325 -125);
DISPLAY 0.872340 (-2325 -125);
DISPLAY INVISIBLE (-2325 -125);
FORCEPROP 1 LAST COMMENT_BODY TRUE
J 2
(-1955 -95);
DISPLAY 0.872340 (-1955 -95);
PAINT GREEN (-1955 -95);
DISPLAY INVISIBLE (-1955 -95);
FORCEPROP 2 LAST PATH I125
J 0
(-1950 75);
DISPLAY 1.021277 (-1950 75);
DISPLAY INVISIBLE (-1950 75);
FORCEADD Q_RES..1
(-575 -150);
FORCEPROP 1 LAST PART_NUMBER CS01002FB07
J 0
(-425 -125);
DISPLAY 0.319149 (-425 -125);
DISPLAY INVISIBLE (-425 -125);
FORCEPROP 1 LAST MATERIAL CHIP
J 0
(-425 -100);
DISPLAY 0.319149 (-425 -100);
FORCEPROP 1 LAST PACK_TYPE 0402LF
J 0
(-300 -150);
DISPLAY 0.510638 (-300 -150);
FORCEPROP 1 LAST TOLERANCE 1%
J 0
(-375 -150);
DISPLAY 0.510638 (-375 -150);
FORCEPROP 1 LAST WATTAGE 1/16W
J 2
(-250 -100);
DISPLAY 0.319149 (-250 -100);
FORCEPROP 1 LAST VALUE 10
J 2
(-400 -150);
DISPLAY 0.510638 (-400 -150);
FORCEPROP 1 LAST $LOCATION R754
J 0
(-775 -150);
DISPLAY 0.638298 (-775 -150);
FORCEPROP 1 LASTPIN (-675 -150) $PN 1
J 0
(-663 -138);
DISPLAY 0.787234 (-663 -138);
FORCEPROP 1 LASTPIN (-475 -150) $PN 2
J 0
(-513 -138);
DISPLAY 0.787234 (-513 -138);
FORCEPROP 2 LAST CDS_LIB pure_quanta
J 0
(-575 -150);
PAINT MONO (-575 -150);
DISPLAY INVISIBLE (-575 -150);
FORCEPROP 1 LAST PATH I126
J 0
(-625 0);
DISPLAY 0.978723 (-625 0);
PAINT WHITE (-625 0);
DISPLAY INVISIBLE (-625 0);
FORCEPROP 2 LAST CDS_LOCATION R754
J 0
(-625 50);
DISPLAY 1.021277 (-625 50);
DISPLAY INVISIBLE (-625 50);
FORCEPROP 2 LAST $SEC 1
J 0
(-625 50);
DISPLAY 0.680851 (-625 50);
PAINT MONO (-625 50);
DISPLAY INVISIBLE (-625 50);
FORCEPROP 2 LAST CDS_SEC 1
J 0
(-625 50);
DISPLAY 1.021277 (-625 50);
DISPLAY INVISIBLE (-625 50);
FORCEADD Q_RES..1
(-575 0);
FORCEPROP 1 LAST PART_NUMBER CS01002FB07
J 0
(-425 25);
DISPLAY 0.319149 (-425 25);
DISPLAY INVISIBLE (-425 25);
FORCEPROP 1 LAST VALUE 10
J 2
(-400 0);
DISPLAY 0.510638 (-400 0);
FORCEPROP 1 LAST MATERIAL CHIP
J 0
(-425 50);
DISPLAY 0.319149 (-425 50);
FORCEPROP 1 LAST WATTAGE 1/16W
J 2
(-250 50);
DISPLAY 0.319149 (-250 50);
FORCEPROP 1 LAST TOLERANCE 1%
J 0
(-375 0);
DISPLAY 0.510638 (-375 0);
FORCEPROP 1 LAST PACK_TYPE 0402LF
J 0
(-300 0);
DISPLAY 0.510638 (-300 0);
FORCEPROP 1 LAST $LOCATION R752
J 0
(-775 0);
DISPLAY 0.638298 (-775 0);
FORCEPROP 1 LASTPIN (-675 0) $PN 1
J 0
(-663 12);
DISPLAY 0.787234 (-663 12);
FORCEPROP 1 LASTPIN (-475 0) $PN 2
J 0
(-513 12);
DISPLAY 0.787234 (-513 12);
FORCEPROP 2 LAST CDS_LIB pure_quanta
J 0
(-575 0);
PAINT MONO (-575 0);
DISPLAY INVISIBLE (-575 0);
FORCEPROP 1 LAST PATH I127
J 0
(-625 150);
DISPLAY 0.978723 (-625 150);
PAINT WHITE (-625 150);
DISPLAY INVISIBLE (-625 150);
FORCEPROP 2 LAST CDS_LOCATION R752
J 0
(-625 200);
DISPLAY 1.021277 (-625 200);
DISPLAY INVISIBLE (-625 200);
FORCEPROP 2 LAST $SEC 1
J 0
(-625 200);
DISPLAY 0.680851 (-625 200);
PAINT MONO (-625 200);
DISPLAY INVISIBLE (-625 200);
FORCEPROP 2 LAST CDS_SEC 1
J 0
(-625 200);
DISPLAY 1.021277 (-625 200);
DISPLAY INVISIBLE (-625 200);
FORCEADD Q_RES..1
(-575 -75);
FORCEPROP 1 LAST PART_NUMBER CS01002FB07
J 0
(-425 -50);
DISPLAY 0.319149 (-425 -50);
DISPLAY INVISIBLE (-425 -50);
FORCEPROP 1 LAST PACK_TYPE 0402LF
J 0
(-300 -75);
DISPLAY 0.510638 (-300 -75);
FORCEPROP 1 LAST VALUE 10
J 2
(-400 -75);
DISPLAY 0.510638 (-400 -75);
FORCEPROP 1 LAST MATERIAL CHIP
J 0
(-425 -25);
DISPLAY 0.319149 (-425 -25);
FORCEPROP 1 LAST WATTAGE 1/16W
J 2
(-250 -25);
DISPLAY 0.319149 (-250 -25);
FORCEPROP 1 LAST TOLERANCE 1%
J 0
(-375 -75);
DISPLAY 0.510638 (-375 -75);
FORCEPROP 1 LAST $LOCATION R753
J 0
(-775 -75);
DISPLAY 0.638298 (-775 -75);
FORCEPROP 1 LASTPIN (-675 -75) $PN 1
J 0
(-663 -63);
DISPLAY 0.787234 (-663 -63);
FORCEPROP 1 LASTPIN (-475 -75) $PN 2
J 0
(-513 -63);
DISPLAY 0.787234 (-513 -63);
FORCEPROP 2 LAST CDS_LIB pure_quanta
J 0
(-575 -75);
PAINT MONO (-575 -75);
DISPLAY INVISIBLE (-575 -75);
FORCEPROP 1 LAST PATH I128
J 0
(-625 75);
DISPLAY 0.978723 (-625 75);
PAINT WHITE (-625 75);
DISPLAY INVISIBLE (-625 75);
FORCEPROP 2 LAST CDS_LOCATION R753
J 0
(-625 125);
DISPLAY 1.021277 (-625 125);
DISPLAY INVISIBLE (-625 125);
FORCEPROP 2 LAST $SEC 1
J 0
(-625 125);
DISPLAY 0.680851 (-625 125);
PAINT MONO (-625 125);
DISPLAY INVISIBLE (-625 125);
FORCEPROP 2 LAST CDS_SEC 1
J 0
(-625 125);
DISPLAY 1.021277 (-625 125);
DISPLAY INVISIBLE (-625 125);
FORCEADD 74CBTLV3126PW..1
(-350 1700);
FORCEPROP 1 LAST PART_NUMBER AL003126K08
J 0
(-598 2108);
DISPLAY 0.723404 (-598 2108);
PAINT GREEN (-598 2108);
DISPLAY INVISIBLE (-598 2108);
FORCEPROP 2 LAST PART_TYPE SMLF
J 0
(-575 2250);
DISPLAY 1.021277 (-575 2250);
FORCEPROP 1 LAST MATERIAL IC
J 0
(-598 2053);
DISPLAY 0.723404 (-598 2053);
PAINT GREEN (-598 2053);
FORCEPROP 2 LAST VALUE 74CBTLV3126PW
J 0
(-575 2200);
DISPLAY 1.021277 (-575 2200);
FORCEPROP 1 LAST $LOCATION U18
J 0
(-598 2158);
DISPLAY 0.723404 (-598 2158);
PAINT GREEN (-598 2158);
FORCEPROP 2 LASTPIN (-750 1450) $PN 2
J 2
(-760 1460);
DISPLAY 0.808511 (-760 1460);
FORCEPROP 2 LASTPIN (50 1450) $PN 3
J 0
(60 1460);
DISPLAY 0.808511 (60 1460);
FORCEPROP 2 LASTPIN (-750 1400) $PN 1
J 2
(-760 1410);
DISPLAY 0.808511 (-760 1410);
FORCEPROP 2 LASTPIN (-750 1600) $PN 5
J 2
(-760 1610);
DISPLAY 0.808511 (-760 1610);
FORCEPROP 2 LASTPIN (50 1600) $PN 6
J 0
(60 1610);
DISPLAY 0.808511 (60 1610);
FORCEPROP 2 LASTPIN (-750 1550) $PN 4
J 2
(-760 1560);
DISPLAY 0.808511 (-760 1560);
FORCEPROP 2 LASTPIN (-750 1750) $PN 9
J 2
(-760 1760);
DISPLAY 0.808511 (-760 1760);
FORCEPROP 2 LASTPIN (50 1750) $PN 8
J 0
(60 1760);
DISPLAY 0.808511 (60 1760);
FORCEPROP 2 LASTPIN (-750 1700) $PN 10
J 2
(-760 1710);
DISPLAY 0.808511 (-760 1710);
FORCEPROP 2 LASTPIN (-750 1900) $PN 12
J 2
(-760 1910);
DISPLAY 0.808511 (-760 1910);
FORCEPROP 2 LASTPIN (50 1900) $PN 11
J 0
(60 1910);
DISPLAY 0.808511 (60 1910);
FORCEPROP 2 LASTPIN (-750 1850) $PN 13
J 2
(-760 1860);
DISPLAY 0.808511 (-760 1860);
FORCEPROP 2 LASTPIN (50 1400) $PN 7
J 0
(60 1410);
DISPLAY 0.808511 (60 1410);
FORCEPROP 2 LASTPIN (50 1950) $PN 14
J 0
(60 1960);
DISPLAY 0.808511 (60 1960);
FORCEPROP 1 LAST CDS_LMAN_SYM_OUTLINE -250,350,250,-350
J 0
(-350 1700);
DISPLAY 0.468085 (-350 1700);
PAINT GREEN (-350 1700);
DISPLAY INVISIBLE (-350 1700);
FORCEPROP 1 LAST NEEDS_NO_SIZE TRUE
J 0
(-100 1390);
DISPLAY 0.723404 (-100 1390);
PAINT GREEN (-100 1390);
DISPLAY INVISIBLE (-100 1390);
FORCEPROP 2 LAST CDS_LIB pure_quanta
J 0
(-350 1700);
PAINT MONO (-350 1700);
DISPLAY INVISIBLE (-350 1700);
FORCEPROP 2 LAST SEC_TYPE 
J 0
(-575 2300);
DISPLAY 1.021277 (-575 2300);
DISPLAY INVISIBLE (-575 2300);
FORCEPROP 1 LAST PATH I129
J 0
(-100 1350);
DISPLAY 0.723404 (-100 1350);
PAINT GREEN (-100 1350);
DISPLAY INVISIBLE (-100 1350);
FORCEPROP 2 LAST CDS_LOCATION U18
J 0
(-575 2300);
DISPLAY 1.021277 (-575 2300);
DISPLAY INVISIBLE (-575 2300);
FORCEPROP 2 LAST SEC 1
J 0
(-575 2300);
DISPLAY 0.680851 (-575 2300);
PAINT MONO (-575 2300);
DISPLAY INVISIBLE (-575 2300);
FORCEADD UNIVERSAL_POWER..1
(125 2450);
FORCEPROP 3 LASTPIN (125 2400) SIG_NAME P3V3_AUX\g
J 0
(135 2410);
DISPLAY 0.659574 (135 2410);
PAINT MONO (135 2410);
DISPLAY INVISIBLE (135 2410);
FORCEPROP 1 LAST HDL_POWER P3V3_AUX
J 1
(125 2500);
DISPLAY 0.872340 (125 2500);
PAINT GREEN (125 2500);
FORCEPROP 2 LAST CDS_LIB logical_power
J 0
(125 2450);
PAINT MONO (125 2450);
DISPLAY INVISIBLE (125 2450);
FORCEPROP 1 LAST PATH I134
J 0
(175 2475);
DISPLAY 0.872340 (175 2475);
PAINT AQUA (175 2475);
DISPLAY INVISIBLE (175 2475);
FORCEADD Q_CAP..1
(275 2200);
FORCEPROP 1 LAST PART_NUMBER CH5104KEB02
J 0
(325 2050);
DISPLAY 0.510638 (325 2050);
DISPLAY INVISIBLE (325 2050);
FORCEPROP 1 LAST PACK_TYPE C0402
J 0
(325 2000);
DISPLAY 0.510638 (325 2000);
FORCEPROP 1 LAST MATERIAL X6S
J 0
(325 2100);
DISPLAY 0.510638 (325 2100);
FORCEPROP 1 LAST TOLERANCE 10%
J 0
(325 2150);
DISPLAY 0.510638 (325 2150);
FORCEPROP 1 LAST VOLTAGE 25V
J 0
(325 2200);
DISPLAY 0.510638 (325 2200);
FORCEPROP 1 LAST VALUE 1UF
J 0
(325 2250);
DISPLAY 0.510638 (325 2250);
FORCEPROP 1 LAST $LOCATION C546
J 0
(325 2300);
DISPLAY 0.978723 (325 2300);
FORCEPROP 1 LASTPIN (275 2300) $PN 1
J 0
(285 2280);
DISPLAY 0.787234 (285 2280);
FORCEPROP 1 LASTPIN (275 2100) $PN 2
J 0
(285 2080);
DISPLAY 0.787234 (285 2080);
FORCEPROP 2 LAST CDS_LIB pure_quanta
J 0
(275 2200);
PAINT MONO (275 2200);
DISPLAY INVISIBLE (275 2200);
FORCEPROP 1 LAST PATH I135
J 0
(325 2350);
DISPLAY 0.978723 (325 2350);
PAINT WHITE (325 2350);
DISPLAY INVISIBLE (325 2350);
FORCEPROP 2 LAST CDS_LOCATION C546
J 0
(325 2400);
DISPLAY 1.021277 (325 2400);
DISPLAY INVISIBLE (325 2400);
FORCEPROP 2 LAST $SEC 1
J 0
(325 2400);
DISPLAY 0.680851 (325 2400);
PAINT MONO (325 2400);
DISPLAY INVISIBLE (325 2400);
FORCEPROP 2 LAST CDS_SEC 1
J 0
(325 2400);
DISPLAY 1.021277 (325 2400);
DISPLAY INVISIBLE (325 2400);
FORCEADD UNIVERSAL_GND..1
(275 2000);
FORCEPROP 3 LASTPIN (275 2050) SIG_NAME GND\g
J 0
(285 2060);
DISPLAY 0.659574 (285 2060);
PAINT MONO (285 2060);
DISPLAY INVISIBLE (285 2060);
FORCEPROP 2 LAST CDS_LIB logical_power
J 0
(275 2000);
PAINT MONO (275 2000);
DISPLAY INVISIBLE (275 2000);
FORCEPROP 1 LAST HDL_POWER GND
J 1
(300 1925);
DISPLAY 0.872340 (300 1925);
PAINT GREEN (300 1925);
DISPLAY INVISIBLE (300 1925);
FORCEPROP 1 LAST PATH I136
J 0
(350 2000);
DISPLAY 0.872340 (350 2000);
PAINT AQUA (350 2000);
DISPLAY INVISIBLE (350 2000);
FORCEADD OFFPAGE..1
(-2000 1600);
FORCEPROP 2 LAST $XR0 131 
J 0
(-2282 1600);
DISPLAY 0.638298 (-2282 1600);
PAINT MONO (-2282 1600);
FORCEPROP 2 LAST CDS_LIB standard
J 0
(-2000 1600);
PAINT MONO (-2000 1600);
DISPLAY INVISIBLE (-2000 1600);
FORCEPROP 1 LAST OFFPAGE TRUE
J 0
(-1675 1475);
DISPLAY 0.872340 (-1675 1475);
PAINT GREEN (-1675 1475);
DISPLAY INVISIBLE (-1675 1475);
FORCEPROP 1 LAST COMMENT_BODY TRUE
J 0
(-1875 1500);
DISPLAY 0.872340 (-1875 1500);
PAINT GREEN (-1875 1500);
DISPLAY INVISIBLE (-1875 1500);
FORCEPROP 2 LAST PATH I140
J 0
(-1950 1675);
DISPLAY 1.021277 (-1950 1675);
DISPLAY INVISIBLE (-1950 1675);
FORCEADD OFFPAGE..1
(-2000 1450);
FORCEPROP 2 LAST $XR0 131 
J 0
(-2282 1450);
DISPLAY 0.638298 (-2282 1450);
PAINT MONO (-2282 1450);
FORCEPROP 2 LAST CDS_LIB standard
J 0
(-2000 1450);
PAINT MONO (-2000 1450);
DISPLAY INVISIBLE (-2000 1450);
FORCEPROP 1 LAST OFFPAGE TRUE
J 0
(-1675 1325);
DISPLAY 0.872340 (-1675 1325);
PAINT GREEN (-1675 1325);
DISPLAY INVISIBLE (-1675 1325);
FORCEPROP 1 LAST COMMENT_BODY TRUE
J 0
(-1875 1350);
DISPLAY 0.872340 (-1875 1350);
PAINT GREEN (-1875 1350);
DISPLAY INVISIBLE (-1875 1350);
FORCEPROP 2 LAST PATH I141
J 0
(-1950 1525);
DISPLAY 1.021277 (-1950 1525);
DISPLAY INVISIBLE (-1950 1525);
FORCEADD OFFPAGE..1
(-2000 1400);
FORCEPROP 2 LAST $XR3 253 
J 0
(-2642 1400);
DISPLAY 0.638298 (-2642 1400);
PAINT MONO (-2642 1400);
FORCEPROP 2 LAST $XR2 132 
J 0
(-2522 1400);
DISPLAY 0.638298 (-2522 1400);
PAINT MONO (-2522 1400);
FORCEPROP 2 LAST $XR1 282 
J 0
(-2402 1400);
DISPLAY 0.638298 (-2402 1400);
PAINT MONO (-2402 1400);
FORCEPROP 2 LAST $XR0 213 
J 0
(-2282 1400);
DISPLAY 0.638298 (-2282 1400);
PAINT MONO (-2282 1400);
FORCEPROP 2 LAST CDS_LIB standard
J 0
(-2000 1400);
PAINT MONO (-2000 1400);
DISPLAY INVISIBLE (-2000 1400);
FORCEPROP 1 LAST OFFPAGE TRUE
J 0
(-1675 1275);
DISPLAY 0.872340 (-1675 1275);
PAINT GREEN (-1675 1275);
DISPLAY INVISIBLE (-1675 1275);
FORCEPROP 1 LAST COMMENT_BODY TRUE
J 0
(-1875 1300);
DISPLAY 0.872340 (-1875 1300);
PAINT GREEN (-1875 1300);
DISPLAY INVISIBLE (-1875 1300);
FORCEPROP 2 LAST PATH I142
J 0
(-1950 1475);
DISPLAY 1.021277 (-1950 1475);
DISPLAY INVISIBLE (-1950 1475);
FORCEADD OFFPAGE..4
(2575 -225);
FORCEPROP 2 LAST $XR0 182 
J 0
(2761 -225);
DISPLAY 0.638298 (2761 -225);
PAINT MONO (2761 -225);
FORCEPROP 2 LAST CDS_LIB standard
J 0
(2575 -225);
PAINT MONO (2575 -225);
DISPLAY INVISIBLE (2575 -225);
FORCEPROP 1 LAST OFFPAGE TRUE
J 0
(2900 -350);
DISPLAY 1.170213 (2900 -350);
PAINT GREEN (2900 -350);
DISPLAY INVISIBLE (2900 -350);
FORCEPROP 1 LAST COMMENT_BODY TRUE
J 0
(2550 -325);
DISPLAY 1.170213 (2550 -325);
PAINT GREEN (2550 -325);
DISPLAY INVISIBLE (2550 -325);
FORCEPROP 2 LAST PATH I143
J 0
(2750 -150);
DISPLAY 1.021277 (2750 -150);
DISPLAY INVISIBLE (2750 -150);
FORCEADD OFFPAGE..2
(2575 -300);
FORCEPROP 2 LAST $XR0 182 
J 0
(2764 -300);
DISPLAY 0.638298 (2764 -300);
PAINT MONO (2764 -300);
FORCEPROP 2 LAST CDS_LIB standard
J 0
(2575 -300);
PAINT MONO (2575 -300);
DISPLAY INVISIBLE (2575 -300);
FORCEPROP 1 LAST OFFPAGE TRUE
J 0
(2900 -425);
DISPLAY 0.872340 (2900 -425);
PAINT GREEN (2900 -425);
DISPLAY INVISIBLE (2900 -425);
FORCEPROP 1 LAST COMMENT_BODY TRUE
J 0
(2530 -395);
DISPLAY 0.872340 (2530 -395);
PAINT GREEN (2530 -395);
DISPLAY INVISIBLE (2530 -395);
FORCEPROP 2 LAST PATH I145
J 0
(2750 -225);
DISPLAY 1.021277 (2750 -225);
DISPLAY INVISIBLE (2750 -225);
FORCEADD Q_RES..1
(-575 -225);
FORCEPROP 1 LAST PART_NUMBER CS01002FB07
J 0
(-425 -200);
DISPLAY 0.319149 (-425 -200);
DISPLAY INVISIBLE (-425 -200);
FORCEPROP 1 LAST WATTAGE 1/16W
J 2
(-250 -175);
DISPLAY 0.319149 (-250 -175);
FORCEPROP 1 LAST PACK_TYPE 0402LF
J 0
(-300 -225);
DISPLAY 0.510638 (-300 -225);
FORCEPROP 1 LAST MATERIAL CHIP
J 0
(-425 -175);
DISPLAY 0.319149 (-425 -175);
FORCEPROP 1 LAST TOLERANCE 1%
J 0
(-375 -225);
DISPLAY 0.510638 (-375 -225);
FORCEPROP 1 LAST VALUE 10
J 2
(-400 -225);
DISPLAY 0.510638 (-400 -225);
FORCEPROP 1 LAST $LOCATION R755
J 0
(-775 -225);
DISPLAY 0.638298 (-775 -225);
FORCEPROP 1 LASTPIN (-675 -225) $PN 1
J 0
(-663 -213);
DISPLAY 0.787234 (-663 -213);
FORCEPROP 1 LASTPIN (-475 -225) $PN 2
J 0
(-513 -213);
DISPLAY 0.787234 (-513 -213);
FORCEPROP 2 LAST CDS_LIB pure_quanta
J 0
(-575 -225);
PAINT MONO (-575 -225);
DISPLAY INVISIBLE (-575 -225);
FORCEPROP 1 LAST PATH I147
J 0
(-625 -75);
DISPLAY 0.978723 (-625 -75);
PAINT WHITE (-625 -75);
DISPLAY INVISIBLE (-625 -75);
FORCEPROP 2 LAST CDS_LOCATION R755
J 0
(-625 -25);
DISPLAY 1.021277 (-625 -25);
DISPLAY INVISIBLE (-625 -25);
FORCEPROP 2 LAST $SEC 1
J 0
(-625 -25);
DISPLAY 0.680851 (-625 -25);
PAINT MONO (-625 -25);
DISPLAY INVISIBLE (-625 -25);
FORCEPROP 2 LAST CDS_SEC 1
J 0
(-625 -25);
DISPLAY 1.021277 (-625 -25);
DISPLAY INVISIBLE (-625 -25);
FORCEADD Q_RES..1
(-575 -300);
FORCEPROP 1 LAST PART_NUMBER CS01002FB07
J 0
(-425 -275);
DISPLAY 0.319149 (-425 -275);
DISPLAY INVISIBLE (-425 -275);
FORCEPROP 1 LAST PACK_TYPE 0402LF
J 0
(-300 -300);
DISPLAY 0.510638 (-300 -300);
FORCEPROP 1 LAST MATERIAL CHIP
J 0
(-425 -250);
DISPLAY 0.319149 (-425 -250);
FORCEPROP 1 LAST WATTAGE 1/16W
J 2
(-250 -250);
DISPLAY 0.319149 (-250 -250);
FORCEPROP 1 LAST TOLERANCE 1%
J 0
(-375 -300);
DISPLAY 0.510638 (-375 -300);
FORCEPROP 1 LAST VALUE 10
J 2
(-400 -300);
DISPLAY 0.510638 (-400 -300);
FORCEPROP 1 LAST $LOCATION R756
J 0
(-775 -300);
DISPLAY 0.638298 (-775 -300);
FORCEPROP 1 LASTPIN (-675 -300) $PN 1
J 0
(-663 -288);
DISPLAY 0.787234 (-663 -288);
FORCEPROP 1 LASTPIN (-475 -300) $PN 2
J 0
(-513 -288);
DISPLAY 0.787234 (-513 -288);
FORCEPROP 2 LAST CDS_LIB pure_quanta
J 0
(-575 -300);
PAINT MONO (-575 -300);
DISPLAY INVISIBLE (-575 -300);
FORCEPROP 1 LAST PATH I148
J 0
(-625 -150);
DISPLAY 0.978723 (-625 -150);
PAINT WHITE (-625 -150);
DISPLAY INVISIBLE (-625 -150);
FORCEPROP 2 LAST CDS_LOCATION R756
J 0
(-625 -100);
DISPLAY 1.021277 (-625 -100);
DISPLAY INVISIBLE (-625 -100);
FORCEPROP 2 LAST $SEC 1
J 0
(-625 -100);
DISPLAY 0.680851 (-625 -100);
PAINT MONO (-625 -100);
DISPLAY INVISIBLE (-625 -100);
FORCEPROP 2 LAST CDS_SEC 1
J 0
(-625 -100);
DISPLAY 1.021277 (-625 -100);
DISPLAY INVISIBLE (-625 -100);
FORCEADD OFFPAGE..2
R 2
(-2000 -225);
FORCEPROP 2 LAST $XR2 239 
J 0
(-2495 -225);
DISPLAY 0.638298 (-2495 -225);
PAINT MONO (-2495 -225);
FORCEPROP 2 LAST $XR1 132 
J 0
(-2375 -225);
DISPLAY 0.638298 (-2375 -225);
PAINT MONO (-2375 -225);
FORCEPROP 2 LAST $XR0 131 
J 0
(-2255 -225);
DISPLAY 0.638298 (-2255 -225);
PAINT MONO (-2255 -225);
FORCEPROP 2 LAST CDS_LIB standard
J 0
(-2000 -225);
PAINT MONO (-2000 -225);
DISPLAY INVISIBLE (-2000 -225);
FORCEPROP 1 LAST OFFPAGE TRUE
J 2
(-2325 -350);
DISPLAY 0.872340 (-2325 -350);
DISPLAY INVISIBLE (-2325 -350);
FORCEPROP 1 LAST COMMENT_BODY TRUE
J 2
(-1955 -320);
DISPLAY 0.872340 (-1955 -320);
PAINT GREEN (-1955 -320);
DISPLAY INVISIBLE (-1955 -320);
FORCEPROP 2 LAST PATH I153
J 0
(-1950 -150);
DISPLAY 1.021277 (-1950 -150);
DISPLAY INVISIBLE (-1950 -150);
FORCEADD OFFPAGE..1
(-2000 -300);
FORCEPROP 2 LAST $XR2 239 
J 0
(-2522 -300);
DISPLAY 0.638298 (-2522 -300);
PAINT MONO (-2522 -300);
FORCEPROP 2 LAST $XR1 132 
J 0
(-2402 -300);
DISPLAY 0.638298 (-2402 -300);
PAINT MONO (-2402 -300);
FORCEPROP 2 LAST $XR0 131 
J 0
(-2282 -300);
DISPLAY 0.638298 (-2282 -300);
PAINT MONO (-2282 -300);
FORCEPROP 2 LAST CDS_LIB standard
J 0
(-2000 -300);
PAINT MONO (-2000 -300);
DISPLAY INVISIBLE (-2000 -300);
FORCEPROP 1 LAST OFFPAGE TRUE
J 0
(-1675 -425);
DISPLAY 0.872340 (-1675 -425);
PAINT GREEN (-1675 -425);
DISPLAY INVISIBLE (-1675 -425);
FORCEPROP 1 LAST COMMENT_BODY TRUE
J 0
(-1875 -400);
DISPLAY 0.872340 (-1875 -400);
PAINT GREEN (-1875 -400);
DISPLAY INVISIBLE (-1875 -400);
FORCEPROP 2 LAST PATH I154
J 0
(-2275 -250);
DISPLAY 1.021277 (-2275 -250);
DISPLAY INVISIBLE (-2275 -250);
FORCEADD OFFPAGE..3
R 2
(-2000 1900);
FORCEPROP 2 LAST $XR2 239 
J 0
(-2550 1900);
DISPLAY 0.638298 (-2550 1900);
PAINT MONO (-2550 1900);
FORCEPROP 2 LAST $XR1 132 
J 0
(-2430 1900);
DISPLAY 0.638298 (-2430 1900);
PAINT MONO (-2430 1900);
FORCEPROP 2 LAST $XR0 131 
J 0
(-2310 1900);
DISPLAY 0.638298 (-2310 1900);
PAINT MONO (-2310 1900);
FORCEPROP 2 LAST CDS_LIB standard
J 0
(-2000 1900);
PAINT MONO (-2000 1900);
DISPLAY INVISIBLE (-2000 1900);
FORCEPROP 1 LAST OFFPAGE TRUE
J 2
(-2325 1775);
DISPLAY 0.872340 (-2325 1775);
DISPLAY INVISIBLE (-2325 1775);
FORCEPROP 1 LAST COMMENT_BODY TRUE
J 2
(-1950 1800);
DISPLAY 0.872340 (-1950 1800);
PAINT GREEN (-1950 1800);
DISPLAY INVISIBLE (-1950 1800);
FORCEPROP 2 LAST PATH I156
J 0
(-2325 1950);
DISPLAY 1.021277 (-2325 1950);
DISPLAY INVISIBLE (-2325 1950);
FORCEADD OFFPAGE..3
R 2
(-2000 1750);
FORCEPROP 2 LAST $XR2 239 
J 0
(-2550 1750);
DISPLAY 0.638298 (-2550 1750);
PAINT MONO (-2550 1750);
FORCEPROP 2 LAST $XR1 132 
J 0
(-2430 1750);
DISPLAY 0.638298 (-2430 1750);
PAINT MONO (-2430 1750);
FORCEPROP 2 LAST $XR0 131 
J 0
(-2310 1750);
DISPLAY 0.638298 (-2310 1750);
PAINT MONO (-2310 1750);
FORCEPROP 2 LAST CDS_LIB standard
J 0
(-2000 1750);
PAINT MONO (-2000 1750);
DISPLAY INVISIBLE (-2000 1750);
FORCEPROP 1 LAST OFFPAGE TRUE
J 2
(-2325 1625);
DISPLAY 0.872340 (-2325 1625);
DISPLAY INVISIBLE (-2325 1625);
FORCEPROP 1 LAST COMMENT_BODY TRUE
J 2
(-1950 1650);
DISPLAY 0.872340 (-1950 1650);
PAINT GREEN (-1950 1650);
DISPLAY INVISIBLE (-1950 1650);
FORCEPROP 2 LAST PATH I157
J 0
(-2325 1800);
DISPLAY 1.021277 (-2325 1800);
DISPLAY INVISIBLE (-2325 1800);
FORCEADD OFFPAGE..3
(2600 1900);
FORCEPROP 2 LAST $XR1 44 
J 0
(2904 1900);
DISPLAY 0.638298 (2904 1900);
PAINT MONO (2904 1900);
FORCEPROP 2 LAST $XR0 13 
J 0
(2814 1900);
DISPLAY 0.638298 (2814 1900);
PAINT MONO (2814 1900);
FORCEPROP 2 LAST CDS_LIB standard
J 0
(2600 1900);
PAINT MONO (2600 1900);
DISPLAY INVISIBLE (2600 1900);
FORCEPROP 1 LAST OFFPAGE TRUE
J 0
(2925 1775);
DISPLAY 0.872340 (2925 1775);
PAINT GREEN (2925 1775);
DISPLAY INVISIBLE (2925 1775);
FORCEPROP 1 LAST COMMENT_BODY TRUE
J 0
(2550 1800);
DISPLAY 0.872340 (2550 1800);
PAINT GREEN (2550 1800);
DISPLAY INVISIBLE (2550 1800);
FORCEPROP 2 LAST PATH I158
J 0
(2800 1975);
DISPLAY 1.021277 (2800 1975);
DISPLAY INVISIBLE (2800 1975);
FORCEADD OFFPAGE..3
(2600 1750);
FORCEPROP 2 LAST $XR1 44 
J 0
(2904 1750);
DISPLAY 0.638298 (2904 1750);
PAINT MONO (2904 1750);
FORCEPROP 2 LAST $XR0 13 
J 0
(2814 1750);
DISPLAY 0.638298 (2814 1750);
PAINT MONO (2814 1750);
FORCEPROP 2 LAST CDS_LIB standard
J 0
(2600 1750);
PAINT MONO (2600 1750);
DISPLAY INVISIBLE (2600 1750);
FORCEPROP 1 LAST OFFPAGE TRUE
J 0
(2925 1625);
DISPLAY 0.872340 (2925 1625);
PAINT GREEN (2925 1625);
DISPLAY INVISIBLE (2925 1625);
FORCEPROP 1 LAST COMMENT_BODY TRUE
J 0
(2550 1650);
DISPLAY 0.872340 (2550 1650);
PAINT GREEN (2550 1650);
DISPLAY INVISIBLE (2550 1650);
FORCEPROP 2 LAST PATH I159
J 0
(2800 1825);
DISPLAY 1.021277 (2800 1825);
DISPLAY INVISIBLE (2800 1825);
FORCEADD OFFPAGE..2
(1225 3500);
FORCEPROP 2 LAST $XR0 133 
J 0
(1414 3500);
DISPLAY 0.638298 (1414 3500);
PAINT MONO (1414 3500);
FORCEPROP 2 LAST CDS_LIB standard
J 0
(1225 3500);
PAINT MONO (1225 3500);
DISPLAY INVISIBLE (1225 3500);
FORCEPROP 1 LAST OFFPAGE TRUE
J 0
(1550 3375);
DISPLAY 0.872340 (1550 3375);
PAINT GREEN (1550 3375);
DISPLAY INVISIBLE (1550 3375);
FORCEPROP 1 LAST COMMENT_BODY TRUE
J 0
(1180 3405);
DISPLAY 0.872340 (1180 3405);
PAINT GREEN (1180 3405);
DISPLAY INVISIBLE (1180 3405);
FORCEPROP 2 LAST PATH I160
J 0
(1400 3575);
DISPLAY 1.021277 (1400 3575);
DISPLAY INVISIBLE (1400 3575);
FORCEADD OFFPAGE..2
(1225 3350);
FORCEPROP 2 LAST $XR1 44 
J 0
(1504 3350);
DISPLAY 0.638298 (1504 3350);
PAINT MONO (1504 3350);
FORCEPROP 2 LAST $XR0 13 
J 0
(1414 3350);
DISPLAY 0.638298 (1414 3350);
PAINT MONO (1414 3350);
FORCEPROP 2 LAST CDS_LIB standard
J 0
(1225 3350);
PAINT MONO (1225 3350);
DISPLAY INVISIBLE (1225 3350);
FORCEPROP 1 LAST OFFPAGE TRUE
J 0
(1550 3225);
DISPLAY 0.872340 (1550 3225);
PAINT GREEN (1550 3225);
DISPLAY INVISIBLE (1550 3225);
FORCEPROP 1 LAST COMMENT_BODY TRUE
J 0
(1180 3255);
DISPLAY 0.872340 (1180 3255);
PAINT GREEN (1180 3255);
DISPLAY INVISIBLE (1180 3255);
FORCEPROP 2 LAST PATH I161
J 0
(1400 3425);
DISPLAY 1.021277 (1400 3425);
DISPLAY INVISIBLE (1400 3425);
FORCEADD OFFPAGE..2
(2600 1450);
FORCEPROP 2 LAST $XR1 47 
J 0
(2879 1450);
DISPLAY 0.638298 (2879 1450);
PAINT MONO (2879 1450);
FORCEPROP 2 LAST $XR0 16 
J 0
(2789 1450);
DISPLAY 0.638298 (2789 1450);
PAINT MONO (2789 1450);
FORCEPROP 2 LAST CDS_LIB standard
J 0
(2600 1450);
PAINT MONO (2600 1450);
DISPLAY INVISIBLE (2600 1450);
FORCEPROP 1 LAST OFFPAGE TRUE
J 0
(2925 1325);
DISPLAY 0.872340 (2925 1325);
PAINT GREEN (2925 1325);
DISPLAY INVISIBLE (2925 1325);
FORCEPROP 1 LAST COMMENT_BODY TRUE
J 0
(2555 1355);
DISPLAY 0.872340 (2555 1355);
PAINT GREEN (2555 1355);
DISPLAY INVISIBLE (2555 1355);
FORCEPROP 2 LAST PATH I162
J 0
(2775 1525);
DISPLAY 1.021277 (2775 1525);
DISPLAY INVISIBLE (2775 1525);
FORCEADD OFFPAGE..2
(2600 1600);
FORCEPROP 2 LAST $XR1 47 
J 0
(2879 1600);
DISPLAY 0.638298 (2879 1600);
PAINT MONO (2879 1600);
FORCEPROP 2 LAST $XR0 16 
J 0
(2789 1600);
DISPLAY 0.638298 (2789 1600);
PAINT MONO (2789 1600);
FORCEPROP 2 LAST CDS_LIB standard
J 0
(2600 1600);
PAINT MONO (2600 1600);
DISPLAY INVISIBLE (2600 1600);
FORCEPROP 1 LAST OFFPAGE TRUE
J 0
(2925 1475);
DISPLAY 0.872340 (2925 1475);
PAINT GREEN (2925 1475);
DISPLAY INVISIBLE (2925 1475);
FORCEPROP 1 LAST COMMENT_BODY TRUE
J 0
(2555 1505);
DISPLAY 0.872340 (2555 1505);
PAINT GREEN (2555 1505);
DISPLAY INVISIBLE (2555 1505);
FORCEPROP 2 LAST PATH I163
J 0
(2775 1675);
DISPLAY 1.021277 (2775 1675);
DISPLAY INVISIBLE (2775 1675);
FORCEADD UNIVERSAL_GND..1
(125 3150);
FORCEPROP 3 LASTPIN (125 3200) SIG_NAME GND\g
J 0
(135 3210);
DISPLAY 0.659574 (135 3210);
PAINT MONO (135 3210);
DISPLAY INVISIBLE (135 3210);
FORCEPROP 2 LAST CDS_LIB logical_power
J 0
(125 3150);
PAINT MONO (125 3150);
DISPLAY INVISIBLE (125 3150);
FORCEPROP 1 LAST HDL_POWER GND
J 1
(150 3075);
DISPLAY 0.872340 (150 3075);
PAINT GREEN (150 3075);
DISPLAY INVISIBLE (150 3075);
FORCEPROP 1 LAST PATH I164
J 0
(200 3150);
DISPLAY 0.872340 (200 3150);
PAINT AQUA (200 3150);
DISPLAY INVISIBLE (200 3150);
FORCEADD UNIVERSAL_GND..1
(125 1250);
FORCEPROP 3 LASTPIN (125 1300) SIG_NAME GND\g
J 0
(135 1310);
DISPLAY 0.659574 (135 1310);
PAINT MONO (135 1310);
DISPLAY INVISIBLE (135 1310);
FORCEPROP 2 LAST CDS_LIB logical_power
J 0
(125 1250);
PAINT MONO (125 1250);
DISPLAY INVISIBLE (125 1250);
FORCEPROP 1 LAST HDL_POWER GND
J 1
(150 1175);
DISPLAY 0.872340 (150 1175);
PAINT GREEN (150 1175);
DISPLAY INVISIBLE (150 1175);
FORCEPROP 1 LAST PATH I165
J 0
(200 1250);
DISPLAY 0.872340 (200 1250);
PAINT AQUA (200 1250);
DISPLAY INVISIBLE (200 1250);
FORCEADD Q_RES..2
(1050 4075);
FORCEPROP 1 LAST PART_NUMBER CS11202FB02
J 0
(1090 3950);
DISPLAY 0.510638 (1090 3950);
DISPLAY INVISIBLE (1090 3950);
FORCEPROP 1 LAST TOLERANCE 1%
J 0
(1095 4100);
DISPLAY 0.510638 (1095 4100);
FORCEPROP 1 LAST VALUE 120
J 0
(1095 4150);
DISPLAY 0.510638 (1095 4150);
FORCEPROP 1 LAST MATERIAL CHIP
J 0
(1090 4000);
DISPLAY 0.510638 (1090 4000);
FORCEPROP 1 LAST WATTAGE 1/16W
J 0
(1090 4050);
DISPLAY 0.510638 (1090 4050);
FORCEPROP 1 LAST PACK_TYPE 0402LF
J 0
(1090 3900);
DISPLAY 0.510638 (1090 3900);
FORCEPROP 1 LAST $LOCATION R757
J 0
(1095 4200);
DISPLAY 0.978723 (1095 4200);
FORCEPROP 1 LASTPIN (1050 4175) $PN 1
J 0
(1055 4137);
DISPLAY 0.787234 (1055 4137);
FORCEPROP 1 LASTPIN (1050 3975) $PN 2
J 0
(1055 3985);
DISPLAY 0.787234 (1055 3985);
FORCEPROP 2 LAST CDS_LIB pure_quanta
J 0
(1050 4075);
PAINT MONO (1050 4075);
DISPLAY INVISIBLE (1050 4075);
FORCEPROP 1 LAST PATH I166
J 0
(1100 4250);
DISPLAY 0.978723 (1100 4250);
PAINT WHITE (1100 4250);
DISPLAY INVISIBLE (1100 4250);
FORCEPROP 2 LAST CDS_LOCATION R757
J 0
(1100 4300);
DISPLAY 1.021277 (1100 4300);
DISPLAY INVISIBLE (1100 4300);
FORCEPROP 2 LAST $SEC 1
J 0
(1100 4300);
DISPLAY 0.680851 (1100 4300);
PAINT MONO (1100 4300);
DISPLAY INVISIBLE (1100 4300);
FORCEPROP 2 LAST CDS_SEC 1
J 0
(1100 4300);
DISPLAY 1.021277 (1100 4300);
DISPLAY INVISIBLE (1100 4300);
FORCEADD UNIVERSAL_POWER..1
(1050 4325);
FORCEPROP 3 LASTPIN (1050 4275) SIG_NAME PVNN_TERM_CPU0\g
J 0
(1060 4285);
DISPLAY 0.659574 (1060 4285);
PAINT MONO (1060 4285);
DISPLAY INVISIBLE (1060 4285);
FORCEPROP 1 LAST HDL_POWER PVNN_TERM_CPU0
J 1
(1050 4375);
DISPLAY 0.872340 (1050 4375);
PAINT GREEN (1050 4375);
FORCEPROP 2 LAST CDS_LIB logical_power
J 0
(1050 4325);
PAINT MONO (1050 4325);
DISPLAY INVISIBLE (1050 4325);
FORCEPROP 1 LAST PATH I167
J 0
(1100 4350);
DISPLAY 0.872340 (1100 4350);
PAINT AQUA (1100 4350);
DISPLAY INVISIBLE (1100 4350);
FORCEADD Q_RES..2
(1125 2225);
FORCEPROP 1 LAST PART_NUMBER CS11502FB07
J 0
(1165 2100);
DISPLAY 0.510638 (1165 2100);
DISPLAY INVISIBLE (1165 2100);
FORCEPROP 1 LAST VALUE 150
J 0
(1170 2300);
DISPLAY 0.510638 (1170 2300);
FORCEPROP 1 LAST TOLERANCE 1%
J 0
(1170 2250);
DISPLAY 0.510638 (1170 2250);
FORCEPROP 1 LAST PACK_TYPE 0402LF
J 0
(1165 2050);
DISPLAY 0.510638 (1165 2050);
FORCEPROP 1 LAST WATTAGE 1/16W
J 0
(1165 2200);
DISPLAY 0.510638 (1165 2200);
FORCEPROP 1 LAST MATERIAL CHIP
J 0
(1165 2150);
DISPLAY 0.510638 (1165 2150);
FORCEPROP 1 LAST $LOCATION R758
J 0
(1170 2350);
DISPLAY 0.978723 (1170 2350);
FORCEPROP 1 LASTPIN (1125 2325) $PN 1
J 0
(1130 2287);
DISPLAY 0.787234 (1130 2287);
FORCEPROP 1 LASTPIN (1125 2125) $PN 2
J 0
(1130 2135);
DISPLAY 0.787234 (1130 2135);
FORCEPROP 2 LAST CDS_LIB pure_quanta
J 0
(1125 2225);
PAINT MONO (1125 2225);
DISPLAY INVISIBLE (1125 2225);
FORCEPROP 1 LAST PATH I168
J 0
(1175 2400);
DISPLAY 0.978723 (1175 2400);
PAINT WHITE (1175 2400);
DISPLAY INVISIBLE (1175 2400);
FORCEPROP 2 LAST CDS_LOCATION R758
J 0
(1175 2450);
DISPLAY 1.021277 (1175 2450);
DISPLAY INVISIBLE (1175 2450);
FORCEPROP 2 LAST $SEC 1
J 0
(1175 2450);
DISPLAY 0.680851 (1175 2450);
PAINT MONO (1175 2450);
DISPLAY INVISIBLE (1175 2450);
FORCEPROP 2 LAST CDS_SEC 1
J 0
(1175 2450);
DISPLAY 1.021277 (1175 2450);
DISPLAY INVISIBLE (1175 2450);
FORCEADD Q_RES..2
(1550 2225);
FORCEPROP 1 LAST PART_NUMBER CS11502FB07
J 0
(1590 2100);
DISPLAY 0.510638 (1590 2100);
DISPLAY INVISIBLE (1590 2100);
FORCEPROP 1 LAST PACK_TYPE 0402LF
J 0
(1590 2050);
DISPLAY 0.510638 (1590 2050);
FORCEPROP 1 LAST MATERIAL CHIP
J 0
(1590 2150);
DISPLAY 0.510638 (1590 2150);
FORCEPROP 1 LAST WATTAGE 1/16W
J 0
(1590 2200);
DISPLAY 0.510638 (1590 2200);
FORCEPROP 1 LAST TOLERANCE 1%
J 0
(1595 2250);
DISPLAY 0.510638 (1595 2250);
FORCEPROP 1 LAST VALUE 150
J 0
(1595 2300);
DISPLAY 0.510638 (1595 2300);
FORCEPROP 1 LAST $LOCATION R759
J 0
(1595 2350);
DISPLAY 0.978723 (1595 2350);
FORCEPROP 1 LASTPIN (1550 2325) $PN 1
J 0
(1555 2287);
DISPLAY 0.787234 (1555 2287);
FORCEPROP 1 LASTPIN (1550 2125) $PN 2
J 0
(1555 2135);
DISPLAY 0.787234 (1555 2135);
FORCEPROP 2 LAST CDS_LIB pure_quanta
J 0
(1550 2225);
PAINT MONO (1550 2225);
DISPLAY INVISIBLE (1550 2225);
FORCEPROP 1 LAST PATH I169
J 0
(1600 2400);
DISPLAY 0.978723 (1600 2400);
PAINT WHITE (1600 2400);
DISPLAY INVISIBLE (1600 2400);
FORCEPROP 2 LAST CDS_LOCATION R759
J 0
(1600 2450);
DISPLAY 1.021277 (1600 2450);
DISPLAY INVISIBLE (1600 2450);
FORCEPROP 2 LAST $SEC 1
J 0
(1600 2450);
DISPLAY 0.680851 (1600 2450);
PAINT MONO (1600 2450);
DISPLAY INVISIBLE (1600 2450);
FORCEPROP 2 LAST CDS_SEC 1
J 0
(1600 2450);
DISPLAY 1.021277 (1600 2450);
DISPLAY INVISIBLE (1600 2450);
FORCEADD UNIVERSAL_POWER..1
(1125 2575);
FORCEPROP 3 LASTPIN (1125 2525) SIG_NAME PVNN_TERM_CPU0\g
J 0
(1135 2535);
DISPLAY 0.659574 (1135 2535);
PAINT MONO (1135 2535);
DISPLAY INVISIBLE (1135 2535);
FORCEPROP 1 LAST HDL_POWER PVNN_TERM_CPU0
J 1
(1125 2625);
DISPLAY 0.872340 (1125 2625);
PAINT GREEN (1125 2625);
FORCEPROP 2 LAST CDS_LIB logical_power
J 0
(1125 2575);
PAINT MONO (1125 2575);
DISPLAY INVISIBLE (1125 2575);
FORCEPROP 1 LAST PATH I172
J 0
(1175 2600);
DISPLAY 0.872340 (1175 2600);
PAINT AQUA (1175 2600);
DISPLAY INVISIBLE (1175 2600);
FORCEADD Q_RES..2
(2000 2200);
FORCEPROP 1 LAST PART_NUMBER CS14992FB06
J 0
(2040 2100);
DISPLAY 0.404255 (2040 2100);
DISPLAY INVISIBLE (2040 2100);
FORCEPROP 1 LAST WATTAGE 1/16W
J 0
(2040 2200);
DISPLAY 0.510638 (2040 2200);
FORCEPROP 1 LAST PACK_TYPE 0402LF
J 0
(2040 2050);
DISPLAY 0.510638 (2040 2050);
FORCEPROP 1 LAST MATERIAL CHIP
J 0
(2040 2150);
DISPLAY 0.510638 (2040 2150);
FORCEPROP 1 LAST VALUE 499
J 0
(2045 2300);
DISPLAY 0.510638 (2045 2300);
FORCEPROP 1 LAST TOLERANCE 1%
J 0
(2045 2250);
DISPLAY 0.510638 (2045 2250);
FORCEPROP 1 LAST $LOCATION R760
J 0
(2045 2350);
DISPLAY 0.978723 (2045 2350);
FORCEPROP 1 LASTPIN (2000 2300) $PN 1
J 0
(2005 2262);
DISPLAY 0.787234 (2005 2262);
FORCEPROP 1 LASTPIN (2000 2100) $PN 2
J 0
(2005 2110);
DISPLAY 0.787234 (2005 2110);
FORCEPROP 2 LAST CDS_LIB pure_quanta
J 0
(2000 2200);
PAINT MONO (2000 2200);
DISPLAY INVISIBLE (2000 2200);
FORCEPROP 1 LAST PATH I174
J 0
(2050 2375);
DISPLAY 0.978723 (2050 2375);
PAINT WHITE (2050 2375);
DISPLAY INVISIBLE (2050 2375);
FORCEPROP 2 LAST CDS_LOCATION R760
J 0
(2050 2425);
DISPLAY 1.021277 (2050 2425);
DISPLAY INVISIBLE (2050 2425);
FORCEPROP 2 LAST $SEC 1
J 0
(2050 2425);
DISPLAY 0.680851 (2050 2425);
PAINT MONO (2050 2425);
DISPLAY INVISIBLE (2050 2425);
FORCEPROP 2 LAST CDS_SEC 1
J 0
(2050 2425);
DISPLAY 1.021277 (2050 2425);
DISPLAY INVISIBLE (2050 2425);
FORCEADD Q_RES..2
(2350 2200);
FORCEPROP 1 LAST PART_NUMBER CS14992FB06
J 0
(2390 2100);
DISPLAY 0.404255 (2390 2100);
DISPLAY INVISIBLE (2390 2100);
FORCEPROP 1 LAST WATTAGE 1/16W
J 0
(2390 2200);
DISPLAY 0.510638 (2390 2200);
FORCEPROP 1 LAST PACK_TYPE 0402LF
J 0
(2390 2050);
DISPLAY 0.510638 (2390 2050);
FORCEPROP 1 LAST MATERIAL CHIP
J 0
(2390 2150);
DISPLAY 0.510638 (2390 2150);
FORCEPROP 1 LAST VALUE 499
J 0
(2395 2300);
DISPLAY 0.510638 (2395 2300);
FORCEPROP 1 LAST TOLERANCE 1%
J 0
(2395 2250);
DISPLAY 0.510638 (2395 2250);
FORCEPROP 1 LAST $LOCATION R761
J 0
(2395 2350);
DISPLAY 0.978723 (2395 2350);
FORCEPROP 1 LASTPIN (2350 2300) $PN 1
J 0
(2355 2262);
DISPLAY 0.787234 (2355 2262);
FORCEPROP 1 LASTPIN (2350 2100) $PN 2
J 0
(2355 2110);
DISPLAY 0.787234 (2355 2110);
FORCEPROP 2 LAST CDS_LIB pure_quanta
J 0
(2350 2200);
PAINT MONO (2350 2200);
DISPLAY INVISIBLE (2350 2200);
FORCEPROP 1 LAST PATH I175
J 0
(2400 2375);
DISPLAY 0.978723 (2400 2375);
PAINT WHITE (2400 2375);
DISPLAY INVISIBLE (2400 2375);
FORCEPROP 2 LAST CDS_LOCATION R761
J 0
(2400 2425);
DISPLAY 1.021277 (2400 2425);
DISPLAY INVISIBLE (2400 2425);
FORCEPROP 2 LAST $SEC 1
J 0
(2400 2425);
DISPLAY 0.680851 (2400 2425);
PAINT MONO (2400 2425);
DISPLAY INVISIBLE (2400 2425);
FORCEPROP 2 LAST CDS_SEC 1
J 0
(2400 2425);
DISPLAY 1.021277 (2400 2425);
DISPLAY INVISIBLE (2400 2425);
FORCEADD Q_RES..2
(825 250);
FORCEPROP 1 LAST PART_NUMBER CS11502FB07
J 0
(865 125);
DISPLAY 0.404255 (865 125);
DISPLAY INVISIBLE (865 125);
FORCEPROP 1 LAST MATERIAL CHIP
J 0
(865 175);
DISPLAY 0.510638 (865 175);
FORCEPROP 1 LAST PACK_TYPE 0402LF
J 0
(865 75);
DISPLAY 0.510638 (865 75);
FORCEPROP 1 LAST TOLERANCE 1%
J 0
(870 275);
DISPLAY 0.510638 (870 275);
FORCEPROP 1 LAST VALUE 150
J 0
(870 325);
DISPLAY 0.510638 (870 325);
FORCEPROP 1 LAST WATTAGE 1/16W
J 0
(865 225);
DISPLAY 0.510638 (865 225);
FORCEPROP 1 LAST $LOCATION R747
J 0
(870 375);
DISPLAY 0.978723 (870 375);
FORCEPROP 1 LASTPIN (825 350) $PN 1
J 0
(830 312);
DISPLAY 0.787234 (830 312);
FORCEPROP 1 LASTPIN (825 150) $PN 2
J 0
(830 160);
DISPLAY 0.787234 (830 160);
FORCEPROP 2 LAST CDS_LIB pure_quanta
J 0
(825 250);
PAINT MONO (825 250);
DISPLAY INVISIBLE (825 250);
FORCEPROP 1 LAST PATH I176
J 0
(875 425);
DISPLAY 0.978723 (875 425);
PAINT WHITE (875 425);
DISPLAY INVISIBLE (875 425);
FORCEPROP 2 LAST CDS_LOCATION R747
J 0
(875 475);
DISPLAY 1.021277 (875 475);
DISPLAY INVISIBLE (875 475);
FORCEPROP 2 LAST $SEC 1
J 0
(875 475);
DISPLAY 0.680851 (875 475);
PAINT MONO (875 475);
DISPLAY INVISIBLE (875 475);
FORCEPROP 2 LAST CDS_SEC 1
J 0
(875 475);
DISPLAY 1.021277 (875 475);
DISPLAY INVISIBLE (875 475);
FORCEADD Q_RES..2
(2225 250);
FORCEPROP 1 LAST PART_NUMBER CS11502FB07
J 0
(2265 125);
DISPLAY 0.404255 (2265 125);
DISPLAY INVISIBLE (2265 125);
FORCEPROP 1 LAST TOLERANCE 1%
J 0
(2270 275);
DISPLAY 0.510638 (2270 275);
FORCEPROP 1 LAST MATERIAL CHIP
J 0
(2265 175);
DISPLAY 0.510638 (2265 175);
FORCEPROP 1 LAST PACK_TYPE 0402LF
J 0
(2265 75);
DISPLAY 0.510638 (2265 75);
FORCEPROP 1 LAST WATTAGE 1/16W
J 0
(2265 225);
DISPLAY 0.510638 (2265 225);
FORCEPROP 1 LAST VALUE 150
J 0
(2270 325);
DISPLAY 0.510638 (2270 325);
FORCEPROP 1 LAST $LOCATION R751
J 0
(2270 375);
DISPLAY 0.978723 (2270 375);
FORCEPROP 1 LASTPIN (2225 350) $PN 1
J 0
(2230 312);
DISPLAY 0.787234 (2230 312);
FORCEPROP 1 LASTPIN (2225 150) $PN 2
J 0
(2230 160);
DISPLAY 0.787234 (2230 160);
FORCEPROP 2 LAST CDS_LIB pure_quanta
J 0
(2225 250);
PAINT MONO (2225 250);
DISPLAY INVISIBLE (2225 250);
FORCEPROP 1 LAST PATH I177
J 0
(2275 425);
DISPLAY 0.978723 (2275 425);
PAINT WHITE (2275 425);
DISPLAY INVISIBLE (2275 425);
FORCEPROP 2 LAST CDS_LOCATION R751
J 0
(2275 475);
DISPLAY 1.021277 (2275 475);
DISPLAY INVISIBLE (2275 475);
FORCEPROP 2 LAST $SEC 1
J 0
(2275 475);
DISPLAY 0.680851 (2275 475);
PAINT MONO (2275 475);
DISPLAY INVISIBLE (2275 475);
FORCEPROP 2 LAST CDS_SEC 1
J 0
(2275 475);
DISPLAY 1.021277 (2275 475);
DISPLAY INVISIBLE (2275 475);
FORCEADD Q_RES..2
(1875 250);
FORCEPROP 1 LAST PART_NUMBER CS11502FB07
J 0
(1915 125);
DISPLAY 0.404255 (1915 125);
DISPLAY INVISIBLE (1915 125);
FORCEPROP 1 LAST PACK_TYPE 0402LF
J 0
(1915 75);
DISPLAY 0.510638 (1915 75);
FORCEPROP 1 LAST MATERIAL CHIP
J 0
(1915 175);
DISPLAY 0.510638 (1915 175);
FORCEPROP 1 LAST VALUE 150
J 0
(1920 325);
DISPLAY 0.510638 (1920 325);
FORCEPROP 1 LAST TOLERANCE 1%
J 0
(1920 275);
DISPLAY 0.510638 (1920 275);
FORCEPROP 1 LAST WATTAGE 1/16W
J 0
(1915 225);
DISPLAY 0.510638 (1915 225);
FORCEPROP 1 LAST $LOCATION R750
J 0
(1920 375);
DISPLAY 0.978723 (1920 375);
FORCEPROP 1 LASTPIN (1875 350) $PN 1
J 0
(1880 312);
DISPLAY 0.787234 (1880 312);
FORCEPROP 1 LASTPIN (1875 150) $PN 2
J 0
(1880 160);
DISPLAY 0.787234 (1880 160);
FORCEPROP 2 LAST CDS_LIB pure_quanta
J 0
(1875 250);
PAINT MONO (1875 250);
DISPLAY INVISIBLE (1875 250);
FORCEPROP 1 LAST PATH I178
J 0
(1925 425);
DISPLAY 0.978723 (1925 425);
PAINT WHITE (1925 425);
DISPLAY INVISIBLE (1925 425);
FORCEPROP 2 LAST CDS_LOCATION R750
J 0
(1925 475);
DISPLAY 1.021277 (1925 475);
DISPLAY INVISIBLE (1925 475);
FORCEPROP 2 LAST $SEC 1
J 0
(1925 475);
DISPLAY 0.680851 (1925 475);
PAINT MONO (1925 475);
DISPLAY INVISIBLE (1925 475);
FORCEPROP 2 LAST CDS_SEC 1
J 0
(1925 475);
DISPLAY 1.021277 (1925 475);
DISPLAY INVISIBLE (1925 475);
FORCEADD Q_RES..2
(1525 250);
FORCEPROP 1 LAST PART_NUMBER CS07502FB04
J 0
(1565 125);
DISPLAY 0.404255 (1565 125);
DISPLAY INVISIBLE (1565 125);
FORCEPROP 1 LAST VALUE 75
J 0
(1570 325);
DISPLAY 0.510638 (1570 325);
FORCEPROP 1 LAST TOLERANCE 1%
J 0
(1570 275);
DISPLAY 0.510638 (1570 275);
FORCEPROP 1 LAST MATERIAL CHIP
J 0
(1565 175);
DISPLAY 0.510638 (1565 175);
FORCEPROP 1 LAST PACK_TYPE 0402LF
J 0
(1565 75);
DISPLAY 0.510638 (1565 75);
FORCEPROP 1 LAST WATTAGE 1/16W
J 0
(1565 225);
DISPLAY 0.510638 (1565 225);
FORCEPROP 1 LAST $LOCATION R749
J 0
(1570 375);
DISPLAY 0.978723 (1570 375);
FORCEPROP 1 LASTPIN (1525 350) $PN 1
J 0
(1530 312);
DISPLAY 0.787234 (1530 312);
FORCEPROP 1 LASTPIN (1525 150) $PN 2
J 0
(1530 160);
DISPLAY 0.787234 (1530 160);
FORCEPROP 2 LAST CDS_LIB pure_quanta
J 0
(1525 250);
PAINT MONO (1525 250);
DISPLAY INVISIBLE (1525 250);
FORCEPROP 1 LAST PATH I179
J 0
(1575 425);
DISPLAY 0.978723 (1575 425);
PAINT WHITE (1575 425);
DISPLAY INVISIBLE (1575 425);
FORCEPROP 2 LAST CDS_LOCATION R749
J 0
(1575 475);
DISPLAY 1.021277 (1575 475);
DISPLAY INVISIBLE (1575 475);
FORCEPROP 2 LAST $SEC 1
J 0
(1575 475);
DISPLAY 0.680851 (1575 475);
PAINT MONO (1575 475);
DISPLAY INVISIBLE (1575 475);
FORCEPROP 2 LAST CDS_SEC 1
J 0
(1575 475);
DISPLAY 1.021277 (1575 475);
DISPLAY INVISIBLE (1575 475);
FORCEADD Q_RES..2
(1175 250);
FORCEPROP 1 LAST PART_NUMBER CS07502FB04
J 0
(1215 125);
DISPLAY 0.404255 (1215 125);
DISPLAY INVISIBLE (1215 125);
FORCEPROP 1 LAST MATERIAL CHIP
J 0
(1215 175);
DISPLAY 0.510638 (1215 175);
FORCEPROP 1 LAST TOLERANCE 1%
J 0
(1220 275);
DISPLAY 0.510638 (1220 275);
FORCEPROP 1 LAST PACK_TYPE 0402LF
J 0
(1215 75);
DISPLAY 0.510638 (1215 75);
FORCEPROP 1 LAST WATTAGE 1/16W
J 0
(1215 225);
DISPLAY 0.510638 (1215 225);
FORCEPROP 1 LAST VALUE 75
J 0
(1220 325);
DISPLAY 0.510638 (1220 325);
FORCEPROP 1 LAST $LOCATION R748
J 0
(1220 375);
DISPLAY 0.978723 (1220 375);
FORCEPROP 1 LASTPIN (1175 350) $PN 1
J 0
(1180 312);
DISPLAY 0.787234 (1180 312);
FORCEPROP 1 LASTPIN (1175 150) $PN 2
J 0
(1180 160);
DISPLAY 0.787234 (1180 160);
FORCEPROP 2 LAST CDS_LIB pure_quanta
J 0
(1175 250);
PAINT MONO (1175 250);
DISPLAY INVISIBLE (1175 250);
FORCEPROP 1 LAST PATH I180
J 0
(1225 425);
DISPLAY 0.978723 (1225 425);
PAINT WHITE (1225 425);
DISPLAY INVISIBLE (1225 425);
FORCEPROP 2 LAST CDS_LOCATION R748
J 0
(1225 475);
DISPLAY 1.021277 (1225 475);
DISPLAY INVISIBLE (1225 475);
FORCEPROP 2 LAST $SEC 1
J 0
(1225 475);
DISPLAY 0.680851 (1225 475);
PAINT MONO (1225 475);
DISPLAY INVISIBLE (1225 475);
FORCEPROP 2 LAST CDS_SEC 1
J 0
(1225 475);
DISPLAY 1.021277 (1225 475);
DISPLAY INVISIBLE (1225 475);
FORCEADD UNIVERSAL_POWER..1
(825 550);
FORCEPROP 3 LASTPIN (825 500) SIG_NAME P1V05_PCH_AUX\g
J 0
(835 510);
DISPLAY 0.659574 (835 510);
PAINT MONO (835 510);
DISPLAY INVISIBLE (835 510);
FORCEPROP 1 LAST HDL_POWER P1V05_PCH_AUX
J 1
(825 600);
DISPLAY 0.872340 (825 600);
PAINT GREEN (825 600);
FORCEPROP 2 LAST CDS_LIB logical_power
J 0
(825 550);
PAINT MONO (825 550);
DISPLAY INVISIBLE (825 550);
FORCEPROP 1 LAST PATH I181
J 0
(875 575);
DISPLAY 0.872340 (875 575);
PAINT AQUA (875 575);
DISPLAY INVISIBLE (875 575);
FORCEADD 74CBTLV3126PW..1
(-350 3600);
FORCEPROP 1 LAST PART_NUMBER AL003126K08
J 0
(-598 4008);
DISPLAY 0.723404 (-598 4008);
PAINT GREEN (-598 4008);
DISPLAY INVISIBLE (-598 4008);
FORCEPROP 2 LAST PART_TYPE SMLF
J 0
(-575 4150);
DISPLAY 1.021277 (-575 4150);
FORCEPROP 1 LAST MATERIAL IC
J 0
(-598 3953);
DISPLAY 0.723404 (-598 3953);
PAINT GREEN (-598 3953);
FORCEPROP 2 LAST VALUE 74CBTLV3126PW
J 0
(-575 4100);
DISPLAY 1.021277 (-575 4100);
FORCEPROP 1 LAST $LOCATION U17
J 0
(-598 4058);
DISPLAY 0.723404 (-598 4058);
PAINT GREEN (-598 4058);
FORCEPROP 2 LASTPIN (-750 3350) $PN 2
J 2
(-760 3360);
DISPLAY 0.808511 (-760 3360);
FORCEPROP 2 LASTPIN (50 3350) $PN 3
J 0
(60 3360);
DISPLAY 0.808511 (60 3360);
FORCEPROP 2 LASTPIN (-750 3300) $PN 1
J 2
(-760 3310);
DISPLAY 0.808511 (-760 3310);
FORCEPROP 2 LASTPIN (-750 3500) $PN 5
J 2
(-760 3510);
DISPLAY 0.808511 (-760 3510);
FORCEPROP 2 LASTPIN (50 3500) $PN 6
J 0
(60 3510);
DISPLAY 0.808511 (60 3510);
FORCEPROP 2 LASTPIN (-750 3450) $PN 4
J 2
(-760 3460);
DISPLAY 0.808511 (-760 3460);
FORCEPROP 2 LASTPIN (-750 3650) $PN 9
J 2
(-760 3660);
DISPLAY 0.808511 (-760 3660);
FORCEPROP 2 LASTPIN (50 3650) $PN 8
J 0
(60 3660);
DISPLAY 0.808511 (60 3660);
FORCEPROP 2 LASTPIN (-750 3600) $PN 10
J 2
(-760 3610);
DISPLAY 0.808511 (-760 3610);
FORCEPROP 2 LASTPIN (-750 3800) $PN 12
J 2
(-760 3810);
DISPLAY 0.808511 (-760 3810);
FORCEPROP 2 LASTPIN (50 3800) $PN 11
J 0
(60 3810);
DISPLAY 0.808511 (60 3810);
FORCEPROP 2 LASTPIN (-750 3750) $PN 13
J 2
(-760 3760);
DISPLAY 0.808511 (-760 3760);
FORCEPROP 2 LASTPIN (50 3300) $PN 7
J 0
(60 3310);
DISPLAY 0.808511 (60 3310);
FORCEPROP 2 LASTPIN (50 3850) $PN 14
J 0
(60 3860);
DISPLAY 0.808511 (60 3860);
FORCEPROP 1 LAST CDS_LMAN_SYM_OUTLINE -250,350,250,-350
J 0
(-350 3600);
DISPLAY 0.468085 (-350 3600);
PAINT GREEN (-350 3600);
DISPLAY INVISIBLE (-350 3600);
FORCEPROP 1 LAST NEEDS_NO_SIZE TRUE
J 0
(-100 3290);
DISPLAY 0.723404 (-100 3290);
PAINT GREEN (-100 3290);
DISPLAY INVISIBLE (-100 3290);
FORCEPROP 2 LAST CDS_LIB pure_quanta
J 0
(-350 3600);
PAINT MONO (-350 3600);
DISPLAY INVISIBLE (-350 3600);
FORCEPROP 2 LAST SEC_TYPE 
J 0
(-575 4200);
DISPLAY 1.021277 (-575 4200);
DISPLAY INVISIBLE (-575 4200);
FORCEPROP 1 LAST PATH I80
J 0
(-100 3250);
DISPLAY 0.723404 (-100 3250);
PAINT GREEN (-100 3250);
DISPLAY INVISIBLE (-100 3250);
FORCEPROP 2 LAST CDS_LOCATION U17
J 0
(-575 4200);
DISPLAY 1.021277 (-575 4200);
DISPLAY INVISIBLE (-575 4200);
FORCEPROP 2 LAST SEC 1
J 0
(-575 4200);
DISPLAY 0.680851 (-575 4200);
PAINT MONO (-575 4200);
DISPLAY INVISIBLE (-575 4200);
FORCEADD UNIVERSAL_POWER..1
(125 4350);
FORCEPROP 3 LASTPIN (125 4300) SIG_NAME P3V3_AUX\g
J 0
(135 4310);
DISPLAY 0.659574 (135 4310);
PAINT MONO (135 4310);
DISPLAY INVISIBLE (135 4310);
FORCEPROP 1 LAST HDL_POWER P3V3_AUX
J 1
(125 4400);
DISPLAY 0.872340 (125 4400);
PAINT GREEN (125 4400);
FORCEPROP 2 LAST CDS_LIB logical_power
J 0
(125 4350);
PAINT MONO (125 4350);
DISPLAY INVISIBLE (125 4350);
FORCEPROP 1 LAST PATH I81
J 0
(175 4375);
DISPLAY 0.872340 (175 4375);
PAINT AQUA (175 4375);
DISPLAY INVISIBLE (175 4375);
FORCEADD OFFPAGE..4
(1225 3800);
FORCEPROP 2 LAST $XR0 133 
J 0
(1411 3800);
DISPLAY 0.638298 (1411 3800);
PAINT MONO (1411 3800);
FORCEPROP 2 LAST CDS_LIB standard
J 0
(1225 3800);
PAINT MONO (1225 3800);
DISPLAY INVISIBLE (1225 3800);
FORCEPROP 1 LAST OFFPAGE TRUE
J 0
(1550 3675);
DISPLAY 1.170213 (1550 3675);
PAINT GREEN (1550 3675);
DISPLAY INVISIBLE (1550 3675);
FORCEPROP 1 LAST COMMENT_BODY TRUE
J 0
(1200 3700);
DISPLAY 1.170213 (1200 3700);
PAINT GREEN (1200 3700);
DISPLAY INVISIBLE (1200 3700);
FORCEPROP 2 LAST PATH I82
J 0
(1400 3875);
DISPLAY 1.021277 (1400 3875);
DISPLAY INVISIBLE (1400 3875);
FORCEADD OFFPAGE..2
R 2
(-2000 3800);
FORCEPROP 2 LAST $XR2 239 
J 0
(-2495 3800);
DISPLAY 0.638298 (-2495 3800);
PAINT MONO (-2495 3800);
FORCEPROP 2 LAST $XR1 131 
J 0
(-2375 3800);
DISPLAY 0.638298 (-2375 3800);
PAINT MONO (-2375 3800);
FORCEPROP 2 LAST $XR0 132 
J 0
(-2255 3800);
DISPLAY 0.638298 (-2255 3800);
PAINT MONO (-2255 3800);
FORCEPROP 2 LAST CDS_LIB standard
J 0
(-2000 3800);
PAINT MONO (-2000 3800);
DISPLAY INVISIBLE (-2000 3800);
FORCEPROP 1 LAST OFFPAGE TRUE
J 2
(-2325 3675);
DISPLAY 0.872340 (-2325 3675);
DISPLAY INVISIBLE (-2325 3675);
FORCEPROP 1 LAST COMMENT_BODY TRUE
J 2
(-1955 3705);
DISPLAY 0.872340 (-1955 3705);
PAINT GREEN (-1955 3705);
DISPLAY INVISIBLE (-1955 3705);
FORCEPROP 2 LAST PATH I86
J 0
(-1950 3875);
DISPLAY 1.021277 (-1950 3875);
DISPLAY INVISIBLE (-1950 3875);
FORCEADD OFFPAGE..1
(-2000 3350);
FORCEPROP 2 LAST $XR2 132 
J 0
(-2522 3350);
DISPLAY 0.638298 (-2522 3350);
PAINT MONO (-2522 3350);
FORCEPROP 2 LAST $XR1 239 
J 0
(-2402 3350);
DISPLAY 0.638298 (-2402 3350);
PAINT MONO (-2402 3350);
FORCEPROP 2 LAST $XR0 131 
J 0
(-2282 3350);
DISPLAY 0.638298 (-2282 3350);
PAINT MONO (-2282 3350);
FORCEPROP 2 LAST CDS_LIB standard
J 0
(-2000 3350);
PAINT MONO (-2000 3350);
DISPLAY INVISIBLE (-2000 3350);
FORCEPROP 1 LAST OFFPAGE TRUE
J 0
(-1675 3225);
DISPLAY 0.872340 (-1675 3225);
PAINT GREEN (-1675 3225);
DISPLAY INVISIBLE (-1675 3225);
FORCEPROP 1 LAST COMMENT_BODY TRUE
J 0
(-1875 3250);
DISPLAY 0.872340 (-1875 3250);
PAINT GREEN (-1875 3250);
DISPLAY INVISIBLE (-1875 3250);
FORCEPROP 2 LAST PATH I87
J 0
(-2275 3400);
DISPLAY 1.021277 (-2275 3400);
DISPLAY INVISIBLE (-2275 3400);
FORCEADD OFFPAGE..1
(-2000 3500);
FORCEPROP 2 LAST $XR2 132 
J 0
(-2522 3500);
DISPLAY 0.638298 (-2522 3500);
PAINT MONO (-2522 3500);
FORCEPROP 2 LAST $XR1 239 
J 0
(-2402 3500);
DISPLAY 0.638298 (-2402 3500);
PAINT MONO (-2402 3500);
FORCEPROP 2 LAST $XR0 131 
J 0
(-2282 3500);
DISPLAY 0.638298 (-2282 3500);
PAINT MONO (-2282 3500);
FORCEPROP 2 LAST CDS_LIB standard
J 0
(-2000 3500);
PAINT MONO (-2000 3500);
DISPLAY INVISIBLE (-2000 3500);
FORCEPROP 1 LAST OFFPAGE TRUE
J 0
(-1675 3375);
DISPLAY 0.872340 (-1675 3375);
PAINT GREEN (-1675 3375);
DISPLAY INVISIBLE (-1675 3375);
FORCEPROP 1 LAST COMMENT_BODY TRUE
J 0
(-1875 3400);
DISPLAY 0.872340 (-1875 3400);
PAINT GREEN (-1875 3400);
DISPLAY INVISIBLE (-1875 3400);
FORCEPROP 2 LAST PATH I88
J 0
(-2275 3550);
DISPLAY 1.021277 (-2275 3550);
DISPLAY INVISIBLE (-2275 3550);
FORCEADD OFFPAGE..1
(-2000 3300);
FORCEPROP 2 LAST $XR3 253 
J 0
(-2642 3300);
DISPLAY 0.638298 (-2642 3300);
PAINT MONO (-2642 3300);
FORCEPROP 2 LAST $XR2 132 
J 0
(-2522 3300);
DISPLAY 0.638298 (-2522 3300);
PAINT MONO (-2522 3300);
FORCEPROP 2 LAST $XR1 282 
J 0
(-2402 3300);
DISPLAY 0.638298 (-2402 3300);
PAINT MONO (-2402 3300);
FORCEPROP 2 LAST $XR0 213 
J 0
(-2282 3300);
DISPLAY 0.638298 (-2282 3300);
PAINT MONO (-2282 3300);
FORCEPROP 2 LAST CDS_LIB standard
J 0
(-2000 3300);
PAINT MONO (-2000 3300);
DISPLAY INVISIBLE (-2000 3300);
FORCEPROP 1 LAST OFFPAGE TRUE
J 0
(-1675 3175);
DISPLAY 0.872340 (-1675 3175);
PAINT GREEN (-1675 3175);
DISPLAY INVISIBLE (-1675 3175);
FORCEPROP 1 LAST COMMENT_BODY TRUE
J 0
(-1875 3200);
DISPLAY 0.872340 (-1875 3200);
PAINT GREEN (-1875 3200);
DISPLAY INVISIBLE (-1875 3200);
FORCEPROP 2 LAST PATH I89
J 0
(-1950 3375);
DISPLAY 1.021277 (-1950 3375);
DISPLAY INVISIBLE (-1950 3375);
FORCEADD Q_RES..2
R 2
(-1900 3025);
FORCEPROP 1 LAST PART_NUMBER CS00002JB13
J 2
(-1940 2900);
DISPLAY 0.638298 (-1940 2900);
DISPLAY INVISIBLE (-1940 2900);
FORCEPROP 1 LAST VALUE 0
J 2
(-1945 3100);
DISPLAY 0.638298 (-1945 3100);
FORCEPROP 1 LAST TOLERANCE 5%
J 2
(-1945 3050);
DISPLAY 0.638298 (-1945 3050);
FORCEPROP 1 LAST PACK_TYPE 0402LF
J 2
(-1940 2850);
DISPLAY 0.638298 (-1940 2850);
FORCEPROP 1 LAST WATTAGE 1/16W
J 2
(-1940 3000);
DISPLAY 0.638298 (-1940 3000);
FORCEPROP 1 LAST MATERIAL CHIP
J 2
(-1940 2950);
DISPLAY 0.638298 (-1940 2950);
FORCEPROP 1 LAST $LOCATION R746
J 2
(-1945 3150);
DISPLAY 0.978723 (-1945 3150);
FORCEPROP 1 LASTPIN (-1900 3125) $PN 1
J 2
(-1905 3087);
DISPLAY 0.787234 (-1905 3087);
FORCEPROP 1 LASTPIN (-1900 2925) $PN 2
J 2
(-1905 2935);
DISPLAY 0.787234 (-1905 2935);
FORCEPROP 2 LAST CDS_LIB pure_quanta
J 2
(-1900 3025);
PAINT MONO (-1900 3025);
DISPLAY INVISIBLE (-1900 3025);
FORCEPROP 1 LAST PATH I90
J 2
(-1950 3200);
DISPLAY 0.978723 (-1950 3200);
PAINT WHITE (-1950 3200);
DISPLAY INVISIBLE (-1950 3200);
FORCEPROP 2 LAST CDS_LOCATION R746
J 2
(-1950 3250);
DISPLAY 1.021277 (-1950 3250);
DISPLAY INVISIBLE (-1950 3250);
FORCEPROP 2 LAST $SEC 1
J 2
(-1950 3250);
DISPLAY 0.680851 (-1950 3250);
PAINT MONO (-1950 3250);
DISPLAY INVISIBLE (-1950 3250);
FORCEPROP 2 LAST CDS_SEC 1
J 2
(-1950 3250);
DISPLAY 1.021277 (-1950 3250);
DISPLAY INVISIBLE (-1950 3250);
FORCEADD UNIVERSAL_GND..1
(-1900 2775);
FORCEPROP 3 LASTPIN (-1900 2825) SIG_NAME GND\g
J 0
(-1890 2835);
DISPLAY 0.659574 (-1890 2835);
PAINT MONO (-1890 2835);
DISPLAY INVISIBLE (-1890 2835);
FORCEPROP 2 LAST CDS_LIB logical_power
J 0
(-1900 2775);
PAINT MONO (-1900 2775);
DISPLAY INVISIBLE (-1900 2775);
FORCEPROP 1 LAST HDL_POWER GND
J 1
(-1875 2700);
DISPLAY 0.872340 (-1875 2700);
PAINT GREEN (-1875 2700);
DISPLAY INVISIBLE (-1875 2700);
FORCEPROP 1 LAST PATH I91
J 0
(-1825 2775);
DISPLAY 0.872340 (-1825 2775);
PAINT AQUA (-1825 2775);
DISPLAY INVISIBLE (-1825 2775);
FORCEADD UNIVERSAL_GND..1
(275 3900);
FORCEPROP 3 LASTPIN (275 3950) SIG_NAME GND\g
J 0
(285 3960);
DISPLAY 0.659574 (285 3960);
PAINT MONO (285 3960);
DISPLAY INVISIBLE (285 3960);
FORCEPROP 2 LAST CDS_LIB logical_power
J 0
(275 3900);
PAINT MONO (275 3900);
DISPLAY INVISIBLE (275 3900);
FORCEPROP 1 LAST HDL_POWER GND
J 1
(300 3825);
DISPLAY 0.872340 (300 3825);
PAINT GREEN (300 3825);
DISPLAY INVISIBLE (300 3825);
FORCEPROP 1 LAST PATH I92
J 0
(350 3900);
DISPLAY 0.872340 (350 3900);
PAINT AQUA (350 3900);
DISPLAY INVISIBLE (350 3900);
FORCEADD Q_CAP..1
(275 4100);
FORCEPROP 1 LAST PART_NUMBER CH5104KEB02
J 0
(325 3950);
DISPLAY 0.510638 (325 3950);
DISPLAY INVISIBLE (325 3950);
FORCEPROP 1 LAST PACK_TYPE C0402
J 0
(325 3900);
DISPLAY 0.510638 (325 3900);
FORCEPROP 1 LAST MATERIAL X6S
J 0
(325 4000);
DISPLAY 0.510638 (325 4000);
FORCEPROP 1 LAST TOLERANCE 10%
J 0
(325 4050);
DISPLAY 0.510638 (325 4050);
FORCEPROP 1 LAST VOLTAGE 25V
J 0
(325 4100);
DISPLAY 0.510638 (325 4100);
FORCEPROP 1 LAST VALUE 1UF
J 0
(325 4150);
DISPLAY 0.510638 (325 4150);
FORCEPROP 1 LAST $LOCATION C545
J 0
(325 4200);
DISPLAY 0.978723 (325 4200);
FORCEPROP 1 LASTPIN (275 4200) $PN 1
J 0
(285 4180);
DISPLAY 0.787234 (285 4180);
FORCEPROP 1 LASTPIN (275 4000) $PN 2
J 0
(285 3980);
DISPLAY 0.787234 (285 3980);
FORCEPROP 2 LAST CDS_LIB pure_quanta
J 0
(275 4100);
PAINT MONO (275 4100);
DISPLAY INVISIBLE (275 4100);
FORCEPROP 1 LAST PATH I93
J 0
(325 4250);
DISPLAY 0.978723 (325 4250);
PAINT WHITE (325 4250);
DISPLAY INVISIBLE (325 4250);
FORCEPROP 2 LAST CDS_LOCATION C545
J 0
(325 4300);
DISPLAY 1.021277 (325 4300);
DISPLAY INVISIBLE (325 4300);
FORCEPROP 2 LAST $SEC 1
J 0
(325 4300);
DISPLAY 0.680851 (325 4300);
PAINT MONO (325 4300);
DISPLAY INVISIBLE (325 4300);
FORCEPROP 2 LAST CDS_SEC 1
J 0
(325 4300);
DISPLAY 1.021277 (325 4300);
DISPLAY INVISIBLE (325 4300);
FORCEADD OFFPAGE..2
(2575 -75);
FORCEPROP 2 LAST $XR0 182 
J 0
(2764 -75);
DISPLAY 0.638298 (2764 -75);
PAINT MONO (2764 -75);
FORCEPROP 2 LAST CDS_LIB standard
J 0
(2575 -75);
PAINT MONO (2575 -75);
DISPLAY INVISIBLE (2575 -75);
FORCEPROP 1 LAST OFFPAGE TRUE
J 0
(2900 -200);
DISPLAY 0.872340 (2900 -200);
PAINT GREEN (2900 -200);
DISPLAY INVISIBLE (2900 -200);
FORCEPROP 1 LAST COMMENT_BODY TRUE
J 0
(2530 -170);
DISPLAY 0.872340 (2530 -170);
PAINT GREEN (2530 -170);
DISPLAY INVISIBLE (2530 -170);
FORCEPROP 2 LAST PATH I95
J 0
(2750 0);
DISPLAY 1.021277 (2750 0);
DISPLAY INVISIBLE (2750 0);
FORCEADD OFFPAGE..2
(2575 -150);
FORCEPROP 2 LAST $XR0 182 
J 0
(2764 -150);
DISPLAY 0.638298 (2764 -150);
PAINT MONO (2764 -150);
FORCEPROP 2 LAST CDS_LIB standard
J 0
(2575 -150);
PAINT MONO (2575 -150);
DISPLAY INVISIBLE (2575 -150);
FORCEPROP 1 LAST OFFPAGE TRUE
J 0
(2900 -275);
DISPLAY 0.872340 (2900 -275);
PAINT GREEN (2900 -275);
DISPLAY INVISIBLE (2900 -275);
FORCEPROP 1 LAST COMMENT_BODY TRUE
J 0
(2530 -245);
DISPLAY 0.872340 (2530 -245);
PAINT GREEN (2530 -245);
DISPLAY INVISIBLE (2530 -245);
FORCEPROP 2 LAST PATH I97
J 0
(2750 -75);
DISPLAY 1.021277 (2750 -75);
DISPLAY INVISIBLE (2750 -75);
FORCEADD QUANTA_TITLE_BLOCK_C..1
(4800 -1575);
FORCEPROP 0 LAST CDS_CON_LAST_MODIFIED Fri Aug 25 14:01:53 2023
J 0
(2915 -1560);
PAINT MONO (2915 -1560);
DISPLAY INVISIBLE (2915 -1560);
FORCEPROP 2 LAST CUSTOM_TXT_CDS <XR_PAGE_TITLE>
J 0
(-3090 3675);
DISPLAY 0.638298 (-3090 3675);
PAINT PINK (-3090 3675);
DISPLAY INVISIBLE (-3090 3675);
FORCEPROP 2 LAST CUSTOM_TXT_CDS <CON_PAGE_NUM> OF <CON_TOTAL_PAGES>
J 0
(4354 -1557);
DISPLAY 0.978723 (4354 -1557);
FORCEPROP 2 LAST CUSTOM_TXT_CDS <Q_REV>
J 0
(4616 -1472);
DISPLAY 1.212766 (4616 -1472);
FORCEPROP 2 LAST CUSTOM_TXT_CDS <Q_PROJ>
J 0
(2418 -1473);
DISPLAY 1.212766 (2418 -1473);
FORCEPROP 2 LAST CUSTOM_TXT_CDS <Q_NUMBER>
J 0
(3397 -1472);
DISPLAY 1.212766 (3397 -1472);
FORCEPROP 2 LAST CUSTOM_TXT_CDS <NAME_1>
J 0
(1625 -1400);
FORCEPROP 2 LAST CUSTOM_TXT_CDS <NAME_2>
J 0
(1625 -1525);
FORCEPROP 2 LAST CUSTOM_TXT_CDS <CON_LAST_MODIFIED>
J 0
(2915 -1560);
DISPLAY 0.978723 (2915 -1560);
FORCEPROP 1 LAST Q_TITLE SPR & PCH - DEBUG PORT (2/3)
J 0
(-4466 -1574);
DISPLAY 2.446809 (-4466 -1574);
PAINT GREEN (-4466 -1574);
FORCEPROP 1 LAST Q_DEPT 
J 1
(1037 -1526);
DISPLAY 1.957447 (1037 -1526);
PAINT GREEN (1037 -1526);
FORCEPROP 2 LAST CDS_XR_PAGE_TITLE CR-132 : @S9S_MB_2U_LIB.S9S_MB_2U(SCH_1):PAGE132
J 0
(-3090 3675);
DISPLAY 0.638298 (-3090 3675);
PAINT PINK (-3090 3675);
DISPLAY INVISIBLE (-3090 3675);
FORCEPROP 2 LAST CDS_LIB pure_quanta
J 0
(4800 -1575);
PAINT MONO (4800 -1575);
DISPLAY INVISIBLE (4800 -1575);
FORCEPROP 1 LAST CDS_LMAN_SYM_OUTLINE -9475,6775,100,-125
J 0
(4800 -1575);
DISPLAY 0.468085 (4800 -1575);
PAINT GREEN (4800 -1575);
DISPLAY INVISIBLE (4800 -1575);
FORCEPROP 2 LAST PAGE_BORDER TRUE
J 0
(-3090 3675);
DISPLAY 0.638298 (-3090 3675);
PAINT PINK (-3090 3675);
DISPLAY INVISIBLE (-3090 3675);
FORCEPROP 1 LAST COMMENT_BODY TRUE
J 0
(4812 -1588);
DISPLAY 0.978723 (4812 -1588);
PAINT GREEN (4812 -1588);
DISPLAY INVISIBLE (4812 -1588);
WIRE 16 -1 (125 4300)(125 4250);
WIRE 16 -1 (825 500)(825 450);
WIRE 16 -1 (1125 2525)(1125 2475);
WIRE 16 -1 (1050 4275)(1050 4175);
WIRE 16 -1 (125 2400)(125 2350);
WIRE 16 -1 (275 4000)(275 3950);
WIRE 16 -1 (-1900 2925)(-1900 2825);
WIRE 16 -1 (125 1300)(125 1400);
WIRE 16 -1 (125 3200)(125 3300);
WIRE 16 -1 (275 2100)(275 2050);
WIRE 16 -1 (2550 1450)(2350 1450);
WIRE 16 -1 (2350 2100)(2350 1450);
WIRE 16 -1 (50 1450)(2350 1450);
FORCEPROP 0 LAST CDS_PHYS_NET_NAME TRC_PCH_PTI1_CLK
J 0
(240 1498);
PAINT MONO (240 1498);
DISPLAY INVISIBLE (240 1498);
FORCEPROP 2 LAST SIG_NAME DBP_CPU_HOOK9_MBP3_GTL_QS_N
J 0
(240 1460);
DISPLAY 0.638298 (240 1460);
PAINT WHITE (240 1460);
WIRE 16 -1 (2350 2300)(2350 2475);
WIRE 16 -1 (2000 2300)(2000 2475);
WIRE 16 -1 (2350 2475)(2000 2475);
WIRE 16 -1 (1550 2325)(1550 2475);
WIRE 16 -1 (2000 2475)(1550 2475);
WIRE 16 -1 (1125 2475)(1125 2325);
WIRE 16 -1 (1125 2475)(1550 2475);
WIRE 16 -1 (2000 2100)(2000 1600);
WIRE 16 -1 (2550 1600)(2000 1600);
WIRE 16 -1 (50 1600)(2000 1600);
FORCEPROP 0 LAST CDS_PHYS_NET_NAME TRC_PCH_PTI1_CLK
J 0
(240 1648);
PAINT MONO (240 1648);
DISPLAY INVISIBLE (240 1648);
FORCEPROP 2 LAST SIG_NAME DBP_CPU_HOOK8_MBP2_GTL_QS_N
J 0
(240 1610);
DISPLAY 0.638298 (240 1610);
PAINT WHITE (240 1610);
WIRE 16 -1 (1175 -75)(-475 -75);
FORCEPROP 0 LAST CDS_PHYS_NET_NAME TRC_PCH_PTI1_CLK
J 0
(-285 -27);
PAINT MONO (-285 -27);
DISPLAY INVISIBLE (-285 -27);
FORCEPROP 2 LAST SIG_NAME JTAG_DBP_TDI_PCH
J 0
(-60 -65);
DISPLAY 0.638298 (-60 -65);
PAINT WHITE (-60 -65);
WIRE 16 -1 (2525 -75)(1175 -75);
WIRE 16 -1 (1175 150)(1175 -75);
WIRE 16 -1 (825 450)(825 350);
WIRE 16 -1 (2225 350)(2225 450);
WIRE 16 -1 (1175 450)(825 450);
WIRE 16 -1 (1175 350)(1175 450);
WIRE 16 -1 (1525 450)(1175 450);
WIRE 16 -1 (1525 350)(1525 450);
WIRE 16 -1 (1875 350)(1875 450);
WIRE 16 -1 (2225 450)(1875 450);
WIRE 16 -1 (1875 450)(1525 450);
WIRE 16 -1 (1525 -150)(-475 -150);
FORCEPROP 0 LAST CDS_PHYS_NET_NAME TRC_PCH_PTI1_CLK
J 0
(-285 -102);
PAINT MONO (-285 -102);
DISPLAY INVISIBLE (-285 -102);
FORCEPROP 2 LAST SIG_NAME JTAG_DBP_TMS_PCH
J 0
(-60 -140);
DISPLAY 0.638298 (-60 -140);
PAINT WHITE (-60 -140);
WIRE 16 -1 (2525 -150)(1525 -150);
WIRE 16 -1 (1525 150)(1525 -150);
WIRE 16 -1 (825 0)(-475 0);
FORCEPROP 0 LAST CDS_PHYS_NET_NAME TRC_PCH_PTI1_CLK
J 0
(-285 48);
PAINT MONO (-285 48);
DISPLAY INVISIBLE (-285 48);
FORCEPROP 2 LAST SIG_NAME JTAG_DBP_TDO_PCH
J 0
(-60 10);
DISPLAY 0.638298 (-60 10);
PAINT WHITE (-60 10);
WIRE 16 -1 (825 150)(825 0);
WIRE 16 -1 (2525 0)(825 0);
WIRE 16 -1 (1550 2125)(1550 1750);
WIRE 16 -1 (2550 1750)(1550 1750);
WIRE 16 -1 (50 1750)(1550 1750);
FORCEPROP 0 LAST CDS_PHYS_NET_NAME TRC_PCH_PTI1_CLK
J 0
(240 1798);
PAINT MONO (240 1798);
DISPLAY INVISIBLE (240 1798);
FORCEPROP 2 LAST SIG_NAME H_CPU_PRDY_QS_GTL_N
J 0
(240 1760);
DISPLAY 0.638298 (240 1760);
PAINT WHITE (240 1760);
WIRE 16 -1 (1125 1900)(50 1900);
FORCEPROP 0 LAST CDS_PHYS_NET_NAME TRC_PCH_PTI1_CLK
J 0
(240 1948);
PAINT MONO (240 1948);
DISPLAY INVISIBLE (240 1948);
FORCEPROP 2 LAST SIG_NAME H_CPU_PREQ_QS_GTL_N
J 0
(240 1910);
DISPLAY 0.638298 (240 1910);
PAINT WHITE (240 1910);
WIRE 16 -1 (1125 2125)(1125 1900);
WIRE 16 -1 (2550 1900)(1125 1900);
WIRE 16 -1 (1875 -225)(-475 -225);
FORCEPROP 0 LAST CDS_PHYS_NET_NAME TRC_PCH_PTI1_CLK
J 0
(-285 -177);
PAINT MONO (-285 -177);
DISPLAY INVISIBLE (-285 -177);
FORCEPROP 2 LAST SIG_NAME H_DBP_PREQ_N_PCH
J 0
(-60 -215);
DISPLAY 0.638298 (-60 -215);
PAINT WHITE (-60 -215);
WIRE 16 -1 (2525 -225)(1875 -225);
WIRE 16 -1 (1875 150)(1875 -225);
WIRE 16 -1 (2225 -300)(-475 -300);
FORCEPROP 0 LAST CDS_PHYS_NET_NAME TRC_PCH_PTI1_CLK
J 0
(-285 -252);
PAINT MONO (-285 -252);
DISPLAY INVISIBLE (-285 -252);
FORCEPROP 2 LAST SIG_NAME H_DBP_PRDY_N_PCH
J 0
(-60 -290);
DISPLAY 0.638298 (-60 -290);
PAINT WHITE (-60 -290);
WIRE 16 -1 (2525 -300)(2225 -300);
WIRE 16 -1 (2225 150)(2225 -300);
WIRE 16 -1 (1050 3350)(50 3350);
FORCEPROP 0 LAST CDS_PHYS_NET_NAME TRC_PCH_PTI1_CLK
J 0
(240 3398);
PAINT MONO (240 3398);
DISPLAY INVISIBLE (240 3398);
FORCEPROP 2 LAST SIG_NAME JTAG_DBP_CPU_QS_GTL_TMS
J 0
(240 3360);
DISPLAY 0.638298 (240 3360);
PAINT WHITE (240 3360);
WIRE 16 -1 (1175 3350)(1050 3350);
WIRE 16 -1 (1050 3975)(1050 3350);
WIRE 16 -1 (-1950 -75)(-675 -75);
FORCEPROP 0 LAST CDS_PHYS_NET_NAME TRC_PCH_PTI1_CLK
J 0
(-1760 -27);
PAINT MONO (-1760 -27);
DISPLAY INVISIBLE (-1760 -27);
FORCEPROP 2 LAST SIG_NAME JTAG_DBP_TDI
J 0
(-1885 -65);
DISPLAY 0.638298 (-1885 -65);
PAINT WHITE (-1885 -65);
WIRE 16 -1 (-675 0)(-1950 0);
FORCEPROP 0 LAST CDS_PHYS_NET_NAME TRC_PCH_PTI1_CLK
J 0
(-1760 48);
PAINT MONO (-1760 48);
DISPLAY INVISIBLE (-1760 48);
FORCEPROP 2 LAST SIG_NAME JTAG_DBP_TDO
J 0
(-1885 10);
DISPLAY 0.638298 (-1885 10);
PAINT WHITE (-1885 10);
WIRE 16 -1 (-675 -150)(-1950 -150);
FORCEPROP 0 LAST CDS_PHYS_NET_NAME TRC_PCH_PTI1_CLK
J 0
(-1760 -102);
PAINT MONO (-1760 -102);
DISPLAY INVISIBLE (-1760 -102);
FORCEPROP 2 LAST SIG_NAME JTAG_DBP_TMS
J 0
(-1885 -140);
DISPLAY 0.638298 (-1885 -140);
PAINT WHITE (-1885 -140);
WIRE 16 -1 (-1900 3125)(-1900 3650);
WIRE 16 -1 (-750 3650)(-1900 3650);
FORCEPROP 0 LAST CDS_PHYS_NET_NAME TRC_PCH_PTI1_CLK
J 0
(-1760 3698);
PAINT MONO (-1760 3698);
DISPLAY INVISIBLE (-1760 3698);
FORCEPROP 2 LAST SIG_NAME PD_74CB_A9
J 0
(-1760 3660);
DISPLAY 0.638298 (-1760 3660);
PAINT WHITE (-1760 3660);
WIRE 16 -1 (-675 -300)(-1950 -300);
FORCEPROP 0 LAST CDS_PHYS_NET_NAME TRC_PCH_PTI1_CLK
J 0
(-1760 -252);
PAINT MONO (-1760 -252);
DISPLAY INVISIBLE (-1760 -252);
FORCEPROP 2 LAST SIG_NAME JTAG_DBP_PRDY_N
J 0
(-1885 -290);
DISPLAY 0.638298 (-1885 -290);
PAINT WHITE (-1885 -290);
WIRE 16 -1 (-675 -225)(-1950 -225);
FORCEPROP 0 LAST CDS_PHYS_NET_NAME TRC_PCH_PTI1_CLK
J 0
(-1760 -177);
PAINT MONO (-1760 -177);
DISPLAY INVISIBLE (-1760 -177);
FORCEPROP 2 LAST SIG_NAME JTAG_DBP_PREQ_N
J 0
(-1885 -215);
DISPLAY 0.638298 (-1885 -215);
PAINT WHITE (-1885 -215);
WIRE 16 -1 (125 1950)(50 1950);
WIRE 16 -1 (125 2350)(125 1950);
WIRE 16 -1 (275 2350)(125 2350);
WIRE 16 -1 (275 2300)(275 2350);
WIRE 16 -1 (125 3300)(50 3300);
WIRE 16 -1 (125 1400)(50 1400);
WIRE 16 -1 (125 3850)(50 3850);
WIRE 16 -1 (125 4250)(125 3850);
WIRE 16 -1 (275 4250)(125 4250);
WIRE 16 -1 (275 4200)(275 4250);
WIRE 16 -1 (1175 3500)(50 3500);
FORCEPROP 0 LAST CDS_PHYS_NET_NAME TRC_PCH_PTI1_CLK
J 0
(240 3548);
PAINT MONO (240 3548);
DISPLAY INVISIBLE (240 3548);
FORCEPROP 2 LAST SIG_NAME JTAG_QS_MUX_GTL_TDI
J 0
(240 3510);
DISPLAY 0.638298 (240 3510);
PAINT WHITE (240 3510);
WIRE 16 -1 (1175 3650)(50 3650);
FORCEPROP 0 LAST CDS_PHYS_NET_NAME TRC_PCH_PTI1_CLK
J 0
(240 3698);
PAINT MONO (240 3698);
DISPLAY INVISIBLE (240 3698);
FORCEPROP 2 LAST SIG_NAME TP_74CB_B8
J 0
(240 3660);
DISPLAY 0.638298 (240 3660);
PAINT WHITE (240 3660);
WIRE 16 -1 (1175 3800)(50 3800);
FORCEPROP 0 LAST CDS_PHYS_NET_NAME TRC_PCH_PTI1_CLK
J 0
(240 3848);
PAINT MONO (240 3848);
DISPLAY INVISIBLE (240 3848);
FORCEPROP 2 LAST SIG_NAME JTAG_MUX_QS_GTL_TDO
J 0
(240 3810);
DISPLAY 0.638298 (240 3810);
PAINT WHITE (240 3810);
WIRE 16 -1 (-925 3300)(-1950 3300);
FORCEPROP 0 LAST CDS_PHYS_NET_NAME TRC_PCH_PTI1_CLK
J 0
(-1760 3348);
PAINT MONO (-1760 3348);
DISPLAY INVISIBLE (-1760 3348);
FORCEPROP 2 LAST SIG_NAME PWRGD_PVNN_MAIN_CPU0
J 0
(-1760 3310);
DISPLAY 0.638298 (-1760 3310);
PAINT WHITE (-1760 3310);
WIRE 16 -1 (-750 3300)(-925 3300);
WIRE 16 -1 (-925 3300)(-925 3450);
WIRE 16 -1 (-925 3450)(-750 3450);
WIRE 16 -1 (-925 3450)(-925 3600);
WIRE 16 -1 (-925 3600)(-750 3600);
WIRE 16 -1 (-925 3600)(-925 3750);
WIRE 16 -1 (-925 3750)(-750 3750);
WIRE 16 -1 (-750 3350)(-1950 3350);
FORCEPROP 0 LAST CDS_PHYS_NET_NAME TRC_PCH_PTI1_CLK
J 0
(-1760 3398);
PAINT MONO (-1760 3398);
DISPLAY INVISIBLE (-1760 3398);
FORCEPROP 2 LAST SIG_NAME JTAG_DBP_TMS
J 0
(-1760 3360);
DISPLAY 0.638298 (-1760 3360);
PAINT WHITE (-1760 3360);
WIRE 16 -1 (-900 1400)(-1950 1400);
FORCEPROP 0 LAST CDS_PHYS_NET_NAME TRC_PCH_PTI1_CLK
J 0
(-1760 1448);
PAINT MONO (-1760 1448);
DISPLAY INVISIBLE (-1760 1448);
FORCEPROP 2 LAST SIG_NAME PWRGD_PVNN_MAIN_CPU0
J 0
(-1860 1410);
DISPLAY 0.638298 (-1860 1410);
PAINT WHITE (-1860 1410);
WIRE 16 -1 (-750 1400)(-900 1400);
WIRE 16 -1 (-900 1400)(-900 1550);
WIRE 16 -1 (-900 1550)(-750 1550);
WIRE 16 -1 (-900 1550)(-900 1700);
WIRE 16 -1 (-900 1700)(-750 1700);
WIRE 16 -1 (-900 1700)(-900 1850);
WIRE 16 -1 (-900 1850)(-750 1850);
WIRE 16 -1 (-750 1900)(-1950 1900);
FORCEPROP 0 LAST CDS_PHYS_NET_NAME TRC_PCH_PTI1_CLK
J 0
(-1760 1948);
PAINT MONO (-1760 1948);
DISPLAY INVISIBLE (-1760 1948);
FORCEPROP 2 LAST SIG_NAME JTAG_DBP_PREQ_N
J 0
(-1860 1910);
DISPLAY 0.638298 (-1860 1910);
PAINT WHITE (-1860 1910);
WIRE 16 -1 (-750 1750)(-1950 1750);
FORCEPROP 0 LAST CDS_PHYS_NET_NAME TRC_PCH_PTI1_CLK
J 0
(-1760 1798);
PAINT MONO (-1760 1798);
DISPLAY INVISIBLE (-1760 1798);
FORCEPROP 2 LAST SIG_NAME JTAG_DBP_PRDY_N
J 0
(-1860 1760);
DISPLAY 0.638298 (-1860 1760);
PAINT WHITE (-1860 1760);
WIRE 16 -1 (-750 1600)(-1950 1600);
FORCEPROP 0 LAST CDS_PHYS_NET_NAME TRC_PCH_PTI1_CLK
J 0
(-1760 1648);
PAINT MONO (-1760 1648);
DISPLAY INVISIBLE (-1760 1648);
FORCEPROP 2 LAST SIG_NAME JTAG_DBP_CPU_HOOK8_MBP2_GTL_N
J 0
(-1860 1610);
DISPLAY 0.638298 (-1860 1610);
PAINT WHITE (-1860 1610);
WIRE 16 -1 (-750 1450)(-1950 1450);
FORCEPROP 0 LAST CDS_PHYS_NET_NAME TRC_PCH_PTI1_CLK
J 0
(-1760 1498);
PAINT MONO (-1760 1498);
DISPLAY INVISIBLE (-1760 1498);
FORCEPROP 2 LAST SIG_NAME JTAG_DBP_CPU_HOOK9_MBP3_GTL_N
J 0
(-1860 1460);
DISPLAY 0.638298 (-1860 1460);
PAINT WHITE (-1860 1460);
WIRE 16 -1 (-750 3500)(-1950 3500);
FORCEPROP 0 LAST CDS_PHYS_NET_NAME TRC_PCH_PTI1_CLK
J 0
(-1760 3548);
PAINT MONO (-1760 3548);
DISPLAY INVISIBLE (-1760 3548);
FORCEPROP 2 LAST SIG_NAME JTAG_DBP_TDI
J 0
(-1760 3510);
DISPLAY 0.638298 (-1760 3510);
PAINT WHITE (-1760 3510);
WIRE 16 -1 (-750 3800)(-1950 3800);
FORCEPROP 0 LAST CDS_PHYS_NET_NAME TRC_PCH_PTI1_CLK
J 0
(-1760 3848);
PAINT MONO (-1760 3848);
DISPLAY INVISIBLE (-1760 3848);
FORCEPROP 2 LAST SIG_NAME JTAG_DBP_TDO
J 0
(-1760 3810);
DISPLAY 0.638298 (-1760 3810);
PAINT WHITE (-1760 3810);
DOT 1 (-900 1550);
DOT 1 (-925 3600);
DOT 1 (-925 3450);
DOT 1 (-925 3300);
DOT 1 (-900 1400);
DOT 1 (-900 1700);
DOT 1 (2350 1450);
DOT 1 (2000 2475);
DOT 1 (1550 2475);
DOT 1 (1050 3350);
DOT 1 (1125 2475);
DOT 1 (2000 1600);
DOT 1 (1550 1750);
DOT 1 (1125 1900);
DOT 1 (125 4250);
DOT 1 (125 2350);
DOT 1 (1175 -75);
DOT 1 (1525 -150);
DOT 1 (1875 -225);
DOT 1 (2225 -300);
DOT 1 (825 0);
DOT 1 (1875 450);
DOT 1 (1525 450);
DOT 1 (1175 450);
DOT 1 (825 450);
QUIT
